FILE_TYPE = MACRO_DRAWING;
SET COLOR_WIRE YELLOW;
SET COLOR_PROP ORANGE;
SET COLOR_DOT WHITE;
SET COLOR_ARC YELLOW;
SET COLOR_BODY GREEN;
SET COLOR_NOTE PURPLE;
SET PROP_DISPLAY VALUE;
SET PAGE_NUMBER P49;
SET PATH_NUMBER P97;
FORCEADD UNIVERSAL_GND..1
(-7775 4775);
FORCEPROP 3 LASTPIN (-7775 4825) SIG_NAME GND\g
J 0
(-7765 4835);
DISPLAY 0.659574 (-7765 4835);
PAINT MONO (-7765 4835);
DISPLAY INVISIBLE (-7765 4835);
FORCEPROP 2 LAST CDS_LIB logical_power
J 0
(-7775 4775);
DISPLAY INVISIBLE (-7775 4775);
FORCEPROP 1 LAST HDL_POWER GND
J 1
(-7750 4700);
DISPLAY 0.702128 (-7750 4700);
PAINT GREEN (-7750 4700);
DISPLAY INVISIBLE (-7750 4700);
FORCEPROP 1 LAST PATH I1
J 0
(-7700 4775);
DISPLAY 0.872340 (-7700 4775);
PAINT AQUA (-7700 4775);
DISPLAY INVISIBLE (-7700 4775);
FORCEADD OFFPAGE..1
(-8725 5200);
FORCEPROP 2 LAST $XR0 10 
J 0
(-8976 5200);
DISPLAY 0.638298 (-8976 5200);
PAINT MONO (-8976 5200);
FORCEPROP 2 LAST CDS_LIB standard
J 0
(-8725 5200);
DISPLAY INVISIBLE (-8725 5200);
FORCEPROP 1 LAST COMMENT_BODY TRUE
J 0
(-8600 5100);
DISPLAY 0.872340 (-8600 5100);
PAINT PEACH (-8600 5100);
DISPLAY INVISIBLE (-8600 5100);
FORCEPROP 1 LAST OFFPAGE TRUE
J 0
(-8400 5075);
DISPLAY 0.872340 (-8400 5075);
PAINT GREEN (-8400 5075);
DISPLAY INVISIBLE (-8400 5075);
FORCEPROP 2 LAST PATH I10
J 0
(-8975 5250);
DISPLAY 0.680851 (-8975 5250);
DISPLAY INVISIBLE (-8975 5250);
FORCEADD 74LVC1G126SE7..1
(-7775 5150);
FORCEPROP 2 LAST PART_TYPE SMLF
J 0
(-7650 5075);
DISPLAY 0.680851 (-7650 5075);
FORCEPROP 2 LAST VALUE 74LVC1G126SE-7
J 0
(-7650 5025);
DISPLAY 0.680851 (-7650 5025);
FORCEPROP 1 LAST MATERIAL IC
J 0
(-7669 4707);
DISPLAY 0.723404 (-7669 4707);
PAINT GREEN (-7669 4707);
FORCEPROP 1 LAST PART_NUMBER AL1G0126009
J 0
(-7669 4834);
DISPLAY 0.723404 (-7669 4834);
PAINT GREEN (-7669 4834);
FORCEPROP 1 LAST CDS_LMAN_SYM_OUTLINE -100,100,100,-100
J 0
(-7775 5150);
DISPLAY 0.468085 (-7775 5150);
PAINT GREEN (-7775 5150);
DISPLAY INVISIBLE (-7775 5150);
FORCEPROP 1 LAST NEEDS_NO_SIZE TRUE
J 0
(-7775 5150);
DISPLAY 0.723404 (-7775 5150);
PAINT GREEN (-7775 5150);
DISPLAY INVISIBLE (-7775 5150);
FORCEPROP 2 LAST CDS_LIB pure_quanta
J 0
(-7775 5150);
DISPLAY INVISIBLE (-7775 5150);
FORCEPROP 1 LAST PATH I11
J 0
(-7775 5150);
DISPLAY 0.723404 (-7775 5150);
PAINT GREEN (-7775 5150);
DISPLAY INVISIBLE (-7775 5150);
FORCEPROP 1 LAST $LOCATION U8
J 0
(-7669 4981);
DISPLAY 0.723404 (-7669 4981);
PAINT GREEN (-7669 4981);
FORCEPROP 0 LASTPIN (-8025 5200) $PN 2
J 2
(-8035 5210);
DISPLAY 0.680851 (-8035 5210);
PAINT MONO (-8035 5210);
FORCEPROP 0 LASTPIN (-7775 4900) $PN 3
R 1
J 2
(-7785 4890);
DISPLAY 0.680851 (-7785 4890);
PAINT MONO (-7785 4890);
FORCEPROP 0 LASTPIN (-8025 5100) $PN 1
J 2
(-8035 5110);
DISPLAY 0.680851 (-8035 5110);
PAINT MONO (-8035 5110);
FORCEPROP 0 LASTPIN (-7775 5400) $PN 5
R 1
J 0
(-7785 5410);
DISPLAY 0.680851 (-7785 5410);
PAINT MONO (-7785 5410);
FORCEPROP 0 LASTPIN (-7525 5150) $PN 4
J 0
(-7515 5160);
DISPLAY 0.680851 (-7515 5160);
PAINT MONO (-7515 5160);
FORCEPROP 0 LAST CDS_LOCATION U8
J 0
(-7650 5125);
DISPLAY 0.680851 (-7650 5125);
DISPLAY INVISIBLE (-7650 5125);
FORCEPROP 0 LAST $SEC 1
J 0
(-7650 5125);
DISPLAY 0.680851 (-7650 5125);
PAINT MONO (-7650 5125);
DISPLAY INVISIBLE (-7650 5125);
FORCEPROP 0 LAST CDS_SEC 1
J 0
(-7650 5125);
DISPLAY 0.680851 (-7650 5125);
DISPLAY INVISIBLE (-7650 5125);
FORCEADD UNIVERSAL_GND..1
(-7875 5475);
FORCEPROP 3 LASTPIN (-7875 5525) SIG_NAME GND\g
J 0
(-7865 5535);
DISPLAY 0.659574 (-7865 5535);
PAINT MONO (-7865 5535);
DISPLAY INVISIBLE (-7865 5535);
FORCEPROP 2 LAST CDS_LIB logical_power
J 0
(-7875 5475);
DISPLAY INVISIBLE (-7875 5475);
FORCEPROP 1 LAST HDL_POWER GND
J 1
(-7850 5400);
DISPLAY 0.702128 (-7850 5400);
PAINT GREEN (-7850 5400);
DISPLAY INVISIBLE (-7850 5400);
FORCEPROP 1 LAST PATH I12
J 0
(-7800 5475);
DISPLAY 0.872340 (-7800 5475);
PAINT AQUA (-7800 5475);
DISPLAY INVISIBLE (-7800 5475);
FORCEADD Q_CAP..1
R 2
(-7875 5700);
FORCEPROP 1 LAST VALUE 0.1UF
J 2
(-7925 5725);
DISPLAY 0.510638 (-7925 5725);
PAINT SKYBLUE (-7925 5725);
FORCEPROP 1 LAST PACK_TYPE 0402
J 2
(-7925 5525);
DISPLAY 0.510638 (-7925 5525);
PAINT SKYBLUE (-7925 5525);
FORCEPROP 1 LAST MATERIAL X7R
J 2
(-7925 5575);
DISPLAY 0.510638 (-7925 5575);
PAINT SKYBLUE (-7925 5575);
FORCEPROP 1 LAST VOLTAGE 25V
J 2
(-7925 5675);
DISPLAY 0.510638 (-7925 5675);
PAINT SKYBLUE (-7925 5675);
FORCEPROP 1 LAST PART_NUMBER CH4104K1B00
J 2
(-7925 5475);
DISPLAY 0.510638 (-7925 5475);
PAINT WHITE (-7925 5475);
FORCEPROP 1 LAST TOLERANCE 10%
J 2
(-7925 5625);
DISPLAY 0.510638 (-7925 5625);
PAINT SKYBLUE (-7925 5625);
FORCEPROP 2 LAST CDS_LIB pure_quanta
J 2
(-7875 5700);
DISPLAY INVISIBLE (-7875 5700);
FORCEPROP 1 LAST PATH I13
J 2
(-7925 5850);
DISPLAY 0.978723 (-7925 5850);
PAINT WHITE (-7925 5850);
DISPLAY INVISIBLE (-7925 5850);
FORCEPROP 1 LAST $LOCATION C274
J 2
(-7925 5775);
DISPLAY 0.702128 (-7925 5775);
PAINT YELLOW (-7925 5775);
FORCEPROP 1 LASTPIN (-7875 5800) $PN 1
J 2
(-7885 5780);
DISPLAY 0.808511 (-7885 5780);
PAINT WHITE (-7885 5780);
FORCEPROP 1 LASTPIN (-7875 5600) $PN 2
J 2
(-7885 5580);
DISPLAY 0.808511 (-7885 5580);
PAINT WHITE (-7885 5580);
FORCEPROP 0 LAST CDS_LOCATION C274
J 0
(-7925 5825);
DISPLAY 0.680851 (-7925 5825);
DISPLAY INVISIBLE (-7925 5825);
FORCEPROP 2 LAST $SEC 1
J 2
(-7925 5900);
DISPLAY 0.680851 (-7925 5900);
PAINT MONO (-7925 5900);
DISPLAY INVISIBLE (-7925 5900);
FORCEPROP 0 LAST CDS_SEC 1
J 2
(-7925 5900);
DISPLAY 0.680851 (-7925 5900);
PAINT MONO (-7925 5900);
DISPLAY INVISIBLE (-7925 5900);
FORCEADD VCCAUX15..1
(-7875 5900);
FORCEPROP 3 LASTPIN (-7875 5850) SIG_NAME P3V3_AUX\g
J 0
(-7865 5860);
DISPLAY 0.659574 (-7865 5860);
PAINT MONO (-7865 5860);
DISPLAY INVISIBLE (-7865 5860);
FORCEPROP 1 LAST HDL_POWER P3V3_AUX
J 1
(-7875 5950);
DISPLAY 0.702128 (-7875 5950);
PAINT GREEN (-7875 5950);
FORCEPROP 2 LAST CDS_LIB logical_power
J 0
(-7875 5900);
DISPLAY INVISIBLE (-7875 5900);
FORCEPROP 1 LAST PATH I14
J 0
(-7825 5925);
DISPLAY 0.872340 (-7825 5925);
PAINT AQUA (-7825 5925);
DISPLAY INVISIBLE (-7825 5925);
FORCEADD UNIVERSAL_GND..1
(-5900 5400);
FORCEPROP 3 LASTPIN (-5900 5450) SIG_NAME GND\g
J 0
(-5890 5460);
DISPLAY 0.659574 (-5890 5460);
PAINT MONO (-5890 5460);
DISPLAY INVISIBLE (-5890 5460);
FORCEPROP 1 LAST PATH I16
J 0
(-5825 5400);
DISPLAY 0.872340 (-5825 5400);
PAINT AQUA (-5825 5400);
DISPLAY INVISIBLE (-5825 5400);
FORCEPROP 1 LAST HDL_POWER GND
J 1
(-5875 5325);
DISPLAY 0.702128 (-5875 5325);
PAINT GREEN (-5875 5325);
DISPLAY INVISIBLE (-5875 5325);
FORCEPROP 2 LAST CDS_LIB logical_power
J 0
(-5900 5400);
DISPLAY INVISIBLE (-5900 5400);
FORCEADD VCCAUX15..1
(-5900 5875);
FORCEPROP 3 LASTPIN (-5900 5825) SIG_NAME P3V3_AUX\g
J 0
(-5890 5835);
DISPLAY 0.659574 (-5890 5835);
PAINT MONO (-5890 5835);
DISPLAY INVISIBLE (-5890 5835);
FORCEPROP 1 LAST HDL_POWER P3V3_AUX
J 1
(-5900 5925);
DISPLAY 0.553191 (-5900 5925);
PAINT GREEN (-5900 5925);
FORCEPROP 1 LAST PATH I17
J 0
(-5850 5900);
DISPLAY 0.872340 (-5850 5900);
PAINT AQUA (-5850 5900);
DISPLAY INVISIBLE (-5850 5900);
FORCEPROP 2 LAST CDS_LIB logical_power
J 0
(-5900 5875);
DISPLAY INVISIBLE (-5900 5875);
FORCEADD OFFPAGE..5
(-8150 1350);
FORCEPROP 2 LAST $XR0 49 
J 0
(-8374 1350);
DISPLAY 0.638298 (-8374 1350);
PAINT MONO (-8374 1350);
FORCEPROP 2 LAST PATH I19
J 0
(-8350 1400);
DISPLAY 0.680851 (-8350 1400);
DISPLAY INVISIBLE (-8350 1400);
FORCEPROP 2 LAST CDS_LIB standard
J 0
(-8150 1350);
DISPLAY INVISIBLE (-8150 1350);
FORCEPROP 1 LAST OFFPAGE TRUE
J 0
(-7825 1225);
DISPLAY 0.872340 (-7825 1225);
PAINT GREEN (-7825 1225);
DISPLAY INVISIBLE (-7825 1225);
FORCEPROP 1 LAST COMMENT_BODY TRUE
J 0
(-8050 1275);
DISPLAY 0.872340 (-8050 1275);
PAINT PEACH (-8050 1275);
DISPLAY INVISIBLE (-8050 1275);
FORCEADD OFFPAGE..1
(-8150 1300);
FORCEPROP 2 LAST $XR1 35 
J 0
(-8491 1300);
DISPLAY 0.638298 (-8491 1300);
PAINT MONO (-8491 1300);
FORCEPROP 2 LAST $XR0 15 
J 0
(-8401 1300);
DISPLAY 0.638298 (-8401 1300);
PAINT MONO (-8401 1300);
FORCEPROP 1 LAST COMMENT_BODY TRUE
J 0
(-8025 1200);
DISPLAY 0.872340 (-8025 1200);
PAINT PEACH (-8025 1200);
DISPLAY INVISIBLE (-8025 1200);
FORCEPROP 1 LAST OFFPAGE TRUE
J 0
(-7825 1175);
DISPLAY 0.872340 (-7825 1175);
PAINT GREEN (-7825 1175);
DISPLAY INVISIBLE (-7825 1175);
FORCEPROP 2 LAST PATH I20
J 0
(-8350 1350);
DISPLAY 0.680851 (-8350 1350);
DISPLAY INVISIBLE (-8350 1350);
FORCEPROP 2 LAST CDS_LIB standard
J 0
(-8150 1300);
DISPLAY INVISIBLE (-8150 1300);
FORCEADD UNIVERSAL_GND..1
(-7950 825);
FORCEPROP 3 LASTPIN (-7950 875) SIG_NAME GND\g
J 0
(-7940 885);
DISPLAY 0.659574 (-7940 885);
PAINT MONO (-7940 885);
DISPLAY INVISIBLE (-7940 885);
FORCEPROP 1 LAST PATH I21
J 0
(-7875 825);
DISPLAY 0.872340 (-7875 825);
PAINT AQUA (-7875 825);
DISPLAY INVISIBLE (-7875 825);
FORCEPROP 1 LAST HDL_POWER GND
J 1
(-7925 750);
DISPLAY 0.702128 (-7925 750);
PAINT GREEN (-7925 750);
DISPLAY INVISIBLE (-7925 750);
FORCEPROP 2 LAST CDS_LIB logical_power
J 0
(-7950 825);
DISPLAY INVISIBLE (-7950 825);
FORCEADD Q_RES..2
(-7950 1075);
FORCEPROP 1 LAST PACK_TYPE 0402LF
J 0
(-7910 900);
DISPLAY 0.510638 (-7910 900);
PAINT SKYBLUE (-7910 900);
FORCEPROP 1 LAST PART_NUMBER CS28202JB05
J 0
(-7910 950);
DISPLAY 0.510638 (-7910 950);
PAINT WHITE (-7910 950);
FORCEPROP 1 LAST MATERIAL CHIP
J 0
(-7910 1000);
DISPLAY 0.510638 (-7910 1000);
PAINT SKYBLUE (-7910 1000);
FORCEPROP 1 LAST WATTAGE 1/16W
J 0
(-7910 1050);
DISPLAY 0.510638 (-7910 1050);
PAINT SKYBLUE (-7910 1050);
FORCEPROP 1 LAST TOLERANCE 5%
J 0
(-7905 1100);
DISPLAY 0.510638 (-7905 1100);
PAINT SKYBLUE (-7905 1100);
FORCEPROP 1 LAST VALUE 8.2K
J 0
(-7905 1150);
DISPLAY 0.510638 (-7905 1150);
PAINT SKYBLUE (-7905 1150);
FORCEPROP 1 LAST PATH I22
J 0
(-7900 1250);
DISPLAY 0.978723 (-7900 1250);
PAINT WHITE (-7900 1250);
DISPLAY INVISIBLE (-7900 1250);
FORCEPROP 2 LAST CDS_LIB pure_quanta
J 0
(-7950 1075);
DISPLAY INVISIBLE (-7950 1075);
FORCEPROP 1 LAST LOCATION R839
J 0
(-7905 1200);
DISPLAY 0.702128 (-7905 1200);
PAINT YELLOW (-7905 1200);
FORCEPROP 1 LASTPIN (-7950 1175) $PN 1
J 0
(-7945 1137);
DISPLAY 0.808511 (-7945 1137);
PAINT WHITE (-7945 1137);
FORCEPROP 1 LASTPIN (-7950 975) $PN 2
J 0
(-7945 985);
DISPLAY 0.808511 (-7945 985);
PAINT WHITE (-7945 985);
FORCEPROP 0 LAST $SEC 1
J 0
(-7900 1250);
DISPLAY 0.680851 (-7900 1250);
PAINT MONO (-7900 1250);
DISPLAY INVISIBLE (-7900 1250);
FORCEPROP 0 LAST CDS_SEC 1
J 0
(-7900 1250);
DISPLAY 0.680851 (-7900 1250);
DISPLAY INVISIBLE (-7900 1250);
FORCEADD UNIVERSAL_GND..1
(-7425 1100);
FORCEPROP 3 LASTPIN (-7425 1150) SIG_NAME GND\g
J 0
(-7415 1160);
DISPLAY 0.659574 (-7415 1160);
PAINT MONO (-7415 1160);
DISPLAY INVISIBLE (-7415 1160);
FORCEPROP 1 LAST PATH I23
J 0
(-7350 1100);
DISPLAY 0.872340 (-7350 1100);
PAINT AQUA (-7350 1100);
DISPLAY INVISIBLE (-7350 1100);
FORCEPROP 2 LAST CDS_LIB logical_power
J 0
(-7425 1100);
DISPLAY INVISIBLE (-7425 1100);
FORCEPROP 1 LAST HDL_POWER GND
J 1
(-7400 1025);
DISPLAY 0.702128 (-7400 1025);
PAINT GREEN (-7400 1025);
DISPLAY INVISIBLE (-7400 1025);
FORCEADD MOSFET_DUAL_6P..1
R 6
(-7050 1300);
FORCEPROP 1 LAST MATERIAL IC
J 0
(-7197 1143);
DISPLAY 0.510638 (-7197 1143);
PAINT SKYBLUE (-7197 1143);
FORCEPROP 1 LAST PART_NUMBER BAM70020047
J 0
(-7197 1099);
DISPLAY 0.510638 (-7197 1099);
PAINT WHITE (-7197 1099);
FORCEPROP 2 LAST PART_TYPE SMLF
J 0
(-7175 952);
DISPLAY 0.510638 (-7175 952);
PAINT SKYBLUE (-7175 952);
FORCEPROP 2 LAST VALUE 2N7002KDW
J 0
(-7175 1002);
DISPLAY 0.510638 (-7175 1002);
PAINT SKYBLUE (-7175 1002);
FORCEPROP 1 LAST PATH I24
J 0
(-7050 1300);
DISPLAY 0.723404 (-7050 1300);
PAINT GREEN (-7050 1300);
DISPLAY INVISIBLE (-7050 1300);
FORCEPROP 1 LAST NEEDS_NO_SIZE TRUE
J 0
(-7050 1279);
DISPLAY 0.468085 (-7050 1279);
PAINT GREEN (-7050 1279);
DISPLAY INVISIBLE (-7050 1279);
FORCEPROP 1 LAST CDS_LMAN_SYM_OUTLINE -150,100,150,-100
J 0
(-7050 1278);
DISPLAY 0.468085 (-7050 1278);
PAINT GREEN (-7050 1278);
DISPLAY INVISIBLE (-7050 1278);
FORCEPROP 2 LAST CDS_LIB pure_quanta
J 0
(-7050 1253);
DISPLAY INVISIBLE (-7050 1253);
FORCEPROP 1 LAST LOCATION Q12
J 0
(-7197 1057);
DISPLAY 0.702128 (-7197 1057);
PAINT YELLOW (-7197 1057);
FORCEPROP 0 LASTPIN (-7350 1350) $PN 6
J 2
(-7360 1360);
DISPLAY 0.680851 (-7360 1360);
PAINT MONO (-7360 1360);
FORCEPROP 0 LASTPIN (-6750 1350) $PN 3
J 0
(-6740 1360);
DISPLAY 0.680851 (-6740 1360);
PAINT MONO (-6740 1360);
FORCEPROP 0 LASTPIN (-7350 1300) $PN 2
J 2
(-7360 1310);
DISPLAY 0.680851 (-7360 1310);
PAINT MONO (-7360 1310);
FORCEPROP 0 LASTPIN (-6750 1300) $PN 5
J 0
(-6740 1310);
DISPLAY 0.680851 (-6740 1310);
PAINT MONO (-6740 1310);
FORCEPROP 0 LASTPIN (-7350 1250) $PN 1
J 2
(-7360 1260);
DISPLAY 0.680851 (-7360 1260);
PAINT MONO (-7360 1260);
FORCEPROP 0 LASTPIN (-6750 1250) $PN 4
J 0
(-6740 1260);
DISPLAY 0.680851 (-6740 1260);
PAINT MONO (-6740 1260);
FORCEPROP 0 LAST $SEC 1
J 0
(-7175 1175);
DISPLAY 0.680851 (-7175 1175);
PAINT MONO (-7175 1175);
DISPLAY INVISIBLE (-7175 1175);
FORCEPROP 0 LAST CDS_SEC 1
J 0
(-7175 1175);
DISPLAY 1.021277 (-7175 1175);
DISPLAY INVISIBLE (-7175 1175);
FORCEADD UNIVERSAL_GND..1
(-6350 825);
FORCEPROP 3 LASTPIN (-6350 875) SIG_NAME GND\g
J 0
(-6340 885);
DISPLAY 0.659574 (-6340 885);
PAINT MONO (-6340 885);
DISPLAY INVISIBLE (-6340 885);
FORCEPROP 1 LAST PATH I25
J 0
(-6275 825);
DISPLAY 0.872340 (-6275 825);
PAINT AQUA (-6275 825);
DISPLAY INVISIBLE (-6275 825);
FORCEPROP 2 LAST CDS_LIB logical_power
J 0
(-6350 825);
DISPLAY INVISIBLE (-6350 825);
FORCEPROP 1 LAST HDL_POWER GND
J 1
(-6325 750);
DISPLAY 0.702128 (-6325 750);
PAINT GREEN (-6325 750);
DISPLAY INVISIBLE (-6325 750);
FORCEADD Q_RES..2
(-6350 1025);
FORCEPROP 1 LAST MATERIAL EMPTY
J 0
(-6310 950);
DISPLAY 0.510638 (-6310 950);
PAINT RED (-6310 950);
FORCEPROP 1 LAST PART_NUMBER CS28202JB05
J 0
(-6310 900);
DISPLAY 0.510638 (-6310 900);
PAINT WHITE (-6310 900);
FORCEPROP 1 LAST PACK_TYPE 0402LF
J 0
(-6310 850);
DISPLAY 0.510638 (-6310 850);
PAINT SKYBLUE (-6310 850);
FORCEPROP 1 LAST VALUE 8.2K
J 0
(-6305 1100);
DISPLAY 0.510638 (-6305 1100);
PAINT SKYBLUE (-6305 1100);
FORCEPROP 1 LAST TOLERANCE 5%
J 0
(-6305 1050);
DISPLAY 0.510638 (-6305 1050);
PAINT SKYBLUE (-6305 1050);
FORCEPROP 1 LAST WATTAGE 1/16W
J 0
(-6310 1000);
DISPLAY 0.510638 (-6310 1000);
PAINT SKYBLUE (-6310 1000);
FORCEPROP 2 LAST CDS_LIB pure_quanta
J 0
(-6350 1025);
DISPLAY INVISIBLE (-6350 1025);
FORCEPROP 1 LAST PATH I26
J 0
(-6300 1200);
DISPLAY 0.978723 (-6300 1200);
PAINT WHITE (-6300 1200);
DISPLAY INVISIBLE (-6300 1200);
FORCEPROP 1 LAST LOCATION R619
J 0
(-6305 1150);
DISPLAY 0.702128 (-6305 1150);
PAINT YELLOW (-6305 1150);
FORCEPROP 1 LASTPIN (-6350 1125) $PN 1
J 0
(-6345 1087);
DISPLAY 0.808511 (-6345 1087);
PAINT WHITE (-6345 1087);
FORCEPROP 1 LASTPIN (-6350 925) $PN 2
J 0
(-6345 935);
DISPLAY 0.808511 (-6345 935);
PAINT WHITE (-6345 935);
FORCEPROP 0 LAST $SEC 1
J 0
(-6300 1200);
DISPLAY 0.680851 (-6300 1200);
PAINT MONO (-6300 1200);
DISPLAY INVISIBLE (-6300 1200);
FORCEPROP 0 LAST CDS_SEC 1
J 0
(-6300 1200);
DISPLAY 0.680851 (-6300 1200);
DISPLAY INVISIBLE (-6300 1200);
FORCEADD UNIVERSAL_GND..1
(-6575 1100);
FORCEPROP 3 LASTPIN (-6575 1150) SIG_NAME GND\g
J 0
(-6565 1160);
DISPLAY 0.659574 (-6565 1160);
PAINT MONO (-6565 1160);
DISPLAY INVISIBLE (-6565 1160);
FORCEPROP 1 LAST PATH I27
J 0
(-6500 1100);
DISPLAY 0.872340 (-6500 1100);
PAINT AQUA (-6500 1100);
DISPLAY INVISIBLE (-6500 1100);
FORCEPROP 2 LAST CDS_LIB logical_power
J 0
(-6575 1100);
DISPLAY INVISIBLE (-6575 1100);
FORCEPROP 1 LAST HDL_POWER GND
J 1
(-6550 1025);
DISPLAY 0.702128 (-6550 1025);
PAINT GREEN (-6550 1025);
DISPLAY INVISIBLE (-6550 1025);
FORCEADD OFFPAGE..4
(-5950 1300);
FORCEPROP 2 LAST $XR0 10 
J 0
(-5764 1300);
DISPLAY 0.638298 (-5764 1300);
PAINT MONO (-5764 1300);
FORCEPROP 2 LAST PATH I28
J 0
(-5750 1350);
DISPLAY 0.680851 (-5750 1350);
DISPLAY INVISIBLE (-5750 1350);
FORCEPROP 2 LAST CDS_LIB standard
J 0
(-5950 1300);
DISPLAY INVISIBLE (-5950 1300);
FORCEPROP 1 LAST OFFPAGE TRUE
J 0
(-5625 1175);
DISPLAY 0.872340 (-5625 1175);
PAINT GREEN (-5625 1175);
DISPLAY INVISIBLE (-5625 1175);
FORCEPROP 1 LAST COMMENT_BODY TRUE
J 0
(-5975 1200);
DISPLAY 0.872340 (-5975 1200);
PAINT PEACH (-5975 1200);
DISPLAY INVISIBLE (-5975 1200);
FORCEADD OFFPAGE..2
(-5950 1350);
FORCEPROP 2 LAST $XR0 49 
J 0
(-5761 1350);
DISPLAY 0.638298 (-5761 1350);
PAINT MONO (-5761 1350);
FORCEPROP 2 LAST PATH I29
J 0
(-5750 1400);
DISPLAY 0.680851 (-5750 1400);
DISPLAY INVISIBLE (-5750 1400);
FORCEPROP 2 LAST CDS_LIB standard
J 0
(-5950 1350);
DISPLAY INVISIBLE (-5950 1350);
FORCEPROP 1 LAST OFFPAGE TRUE
J 0
(-5625 1225);
DISPLAY 0.872340 (-5625 1225);
PAINT GREEN (-5625 1225);
DISPLAY INVISIBLE (-5625 1225);
FORCEPROP 1 LAST COMMENT_BODY TRUE
J 0
(-5995 1255);
DISPLAY 0.872340 (-5995 1255);
PAINT PEACH (-5995 1255);
DISPLAY INVISIBLE (-5995 1255);
FORCEADD UNIVERSAL_GND..1
(-6925 4425);
FORCEPROP 3 LASTPIN (-6925 4475) SIG_NAME GND\g
J 0
(-6915 4485);
DISPLAY 0.659574 (-6915 4485);
PAINT MONO (-6915 4485);
DISPLAY INVISIBLE (-6915 4485);
FORCEPROP 2 LAST CDS_LIB logical_power
J 0
(-6925 4425);
DISPLAY INVISIBLE (-6925 4425);
FORCEPROP 1 LAST HDL_POWER GND
J 1
(-6900 4350);
DISPLAY 0.702128 (-6900 4350);
PAINT GREEN (-6900 4350);
DISPLAY INVISIBLE (-6900 4350);
FORCEPROP 1 LAST PATH I3
J 0
(-6850 4425);
DISPLAY 0.872340 (-6850 4425);
PAINT AQUA (-6850 4425);
DISPLAY INVISIBLE (-6850 4425);
FORCEADD VCCAUX15..1
(-3200 5875);
FORCEPROP 3 LASTPIN (-3200 5825) SIG_NAME P3V3_AUX\g
J 0
(-3190 5835);
DISPLAY 0.659574 (-3190 5835);
PAINT MONO (-3190 5835);
DISPLAY INVISIBLE (-3190 5835);
FORCEPROP 1 LAST HDL_POWER P3V3_AUX
J 1
(-3200 5925);
DISPLAY 0.702128 (-3200 5925);
PAINT GREEN (-3200 5925);
FORCEPROP 1 LAST PATH I31
J 0
(-3150 5900);
DISPLAY 0.872340 (-3150 5900);
PAINT AQUA (-3150 5900);
DISPLAY INVISIBLE (-3150 5900);
FORCEPROP 2 LAST CDS_LIB logical_power
J 0
(-3200 5875);
DISPLAY INVISIBLE (-3200 5875);
FORCEADD OFFPAGE..1
(-8950 2900);
FORCEPROP 2 LAST $XR0 49 
J 0
(-9201 2900);
DISPLAY 0.638298 (-9201 2900);
PAINT MONO (-9201 2900);
FORCEPROP 2 LAST PATH I32
J 0
(-9150 2950);
DISPLAY 0.680851 (-9150 2950);
DISPLAY INVISIBLE (-9150 2950);
FORCEPROP 1 LAST COMMENT_BODY TRUE
J 0
(-8825 2800);
DISPLAY 0.872340 (-8825 2800);
PAINT PEACH (-8825 2800);
DISPLAY INVISIBLE (-8825 2800);
FORCEPROP 1 LAST OFFPAGE TRUE
J 0
(-8625 2775);
DISPLAY 0.872340 (-8625 2775);
PAINT GREEN (-8625 2775);
DISPLAY INVISIBLE (-8625 2775);
FORCEPROP 2 LAST CDS_LIB standard
J 0
(-8950 2900);
DISPLAY INVISIBLE (-8950 2900);
FORCEADD OFFPAGE..1
(-8650 2450);
FORCEPROP 2 LAST $XR0 49 
J 0
(-8871 2450);
DISPLAY 0.638298 (-8871 2450);
PAINT MONO (-8871 2450);
FORCEPROP 2 LAST PATH I33
J 0
(-8850 2500);
DISPLAY 0.680851 (-8850 2500);
DISPLAY INVISIBLE (-8850 2500);
FORCEPROP 1 LAST COMMENT_BODY TRUE
J 0
(-8525 2350);
DISPLAY 0.872340 (-8525 2350);
PAINT PEACH (-8525 2350);
DISPLAY INVISIBLE (-8525 2350);
FORCEPROP 1 LAST OFFPAGE TRUE
J 0
(-8325 2325);
DISPLAY 0.872340 (-8325 2325);
PAINT GREEN (-8325 2325);
DISPLAY INVISIBLE (-8325 2325);
FORCEPROP 2 LAST CDS_LIB standard
J 0
(-8650 2450);
DISPLAY INVISIBLE (-8650 2450);
FORCEADD Q_RES..1
(-8075 2900);
FORCEPROP 1 LAST MATERIAL CHIP
J 0
(-7875 2900);
DISPLAY 0.510638 (-7875 2900);
PAINT SKYBLUE (-7875 2900);
FORCEPROP 1 LAST VALUE 33.2
J 0
(-7975 2900);
DISPLAY 0.510638 (-7975 2900);
PAINT SKYBLUE (-7975 2900);
FORCEPROP 1 LAST TOLERANCE 1%
J 0
(-7950 2900);
DISPLAY 0.510638 (-7950 2900);
PAINT SKYBLUE (-7950 2900);
DISPLAY INVISIBLE (-7950 2900);
FORCEPROP 1 LAST PART_NUMBER CS03322FB03
J 0
(-8125 3000);
DISPLAY 0.510638 (-8125 3000);
PAINT WHITE (-8125 3000);
DISPLAY INVISIBLE (-8125 3000);
FORCEPROP 2 LAST CDS_LIB pure_quanta
J 0
(-8075 2900);
DISPLAY INVISIBLE (-8075 2900);
FORCEPROP 1 LAST WATTAGE 1/16W
J 2
(-8100 2750);
DISPLAY 0.510638 (-8100 2750);
PAINT SKYBLUE (-8100 2750);
DISPLAY INVISIBLE (-8100 2750);
FORCEPROP 1 LAST PACK_TYPE 0402LF
J 0
(-7825 2750);
DISPLAY 0.510638 (-7825 2750);
PAINT SKYBLUE (-7825 2750);
DISPLAY INVISIBLE (-7825 2750);
FORCEPROP 1 LAST PATH I34
J 0
(-8125 3050);
DISPLAY 0.978723 (-8125 3050);
PAINT WHITE (-8125 3050);
DISPLAY INVISIBLE (-8125 3050);
FORCEPROP 1 LAST LOCATION R812
J 0
(-8300 2900);
DISPLAY 0.702128 (-8300 2900);
PAINT YELLOW (-8300 2900);
FORCEPROP 1 LASTPIN (-8175 2900) $PN 1
J 0
(-8163 2912);
DISPLAY 0.808511 (-8163 2912);
PAINT WHITE (-8163 2912);
FORCEPROP 1 LASTPIN (-7975 2900) $PN 2
J 0
(-8013 2912);
DISPLAY 0.808511 (-8013 2912);
PAINT WHITE (-8013 2912);
FORCEPROP 0 LAST $SEC 1
J 0
(-8125 3000);
DISPLAY 0.680851 (-8125 3000);
PAINT MONO (-8125 3000);
DISPLAY INVISIBLE (-8125 3000);
FORCEPROP 0 LAST CDS_SEC 1
J 0
(-8125 3000);
DISPLAY 0.680851 (-8125 3000);
DISPLAY INVISIBLE (-8125 3000);
FORCEADD Q_RES..1
(-7875 2450);
FORCEPROP 1 LAST VALUE 33.2
J 0
(-7775 2450);
DISPLAY 0.510638 (-7775 2450);
PAINT SKYBLUE (-7775 2450);
FORCEPROP 1 LAST MATERIAL CHIP
J 0
(-7675 2450);
DISPLAY 0.510638 (-7675 2450);
PAINT SKYBLUE (-7675 2450);
FORCEPROP 1 LAST PATH I35
J 0
(-7925 2600);
DISPLAY 0.978723 (-7925 2600);
PAINT WHITE (-7925 2600);
DISPLAY INVISIBLE (-7925 2600);
FORCEPROP 1 LAST PACK_TYPE 0402LF
J 0
(-7625 2300);
DISPLAY 0.510638 (-7625 2300);
PAINT SKYBLUE (-7625 2300);
DISPLAY INVISIBLE (-7625 2300);
FORCEPROP 1 LAST WATTAGE 1/16W
J 2
(-7900 2300);
DISPLAY 0.510638 (-7900 2300);
PAINT SKYBLUE (-7900 2300);
DISPLAY INVISIBLE (-7900 2300);
FORCEPROP 2 LAST CDS_LIB pure_quanta
J 0
(-7875 2450);
DISPLAY INVISIBLE (-7875 2450);
FORCEPROP 1 LAST PART_NUMBER CS03322FB03
J 0
(-7925 2550);
DISPLAY 0.510638 (-7925 2550);
PAINT WHITE (-7925 2550);
DISPLAY INVISIBLE (-7925 2550);
FORCEPROP 1 LAST TOLERANCE 1%
J 0
(-7750 2450);
DISPLAY 0.510638 (-7750 2450);
PAINT SKYBLUE (-7750 2450);
DISPLAY INVISIBLE (-7750 2450);
FORCEPROP 1 LAST LOCATION R813
J 0
(-8100 2450);
DISPLAY 0.702128 (-8100 2450);
PAINT YELLOW (-8100 2450);
FORCEPROP 1 LASTPIN (-7975 2450) $PN 1
J 0
(-7963 2462);
DISPLAY 0.808511 (-7963 2462);
PAINT WHITE (-7963 2462);
FORCEPROP 1 LASTPIN (-7775 2450) $PN 2
J 0
(-7813 2462);
DISPLAY 0.808511 (-7813 2462);
PAINT WHITE (-7813 2462);
FORCEPROP 0 LAST $SEC 1
J 0
(-7925 2550);
DISPLAY 0.680851 (-7925 2550);
PAINT MONO (-7925 2550);
DISPLAY INVISIBLE (-7925 2550);
FORCEPROP 0 LAST CDS_SEC 1
J 0
(-7925 2550);
DISPLAY 0.680851 (-7925 2550);
DISPLAY INVISIBLE (-7925 2550);
FORCEADD Q_RES..2
(-7100 3175);
FORCEPROP 1 LAST MATERIAL CHIP
J 0
(-7060 3100);
DISPLAY 0.510638 (-7060 3100);
PAINT SKYBLUE (-7060 3100);
FORCEPROP 1 LAST WATTAGE 1/16W
J 0
(-7060 3150);
DISPLAY 0.510638 (-7060 3150);
PAINT SKYBLUE (-7060 3150);
FORCEPROP 1 LAST VALUE 10K
J 0
(-7055 3250);
DISPLAY 0.510638 (-7055 3250);
PAINT SKYBLUE (-7055 3250);
FORCEPROP 1 LAST PACK_TYPE 0402LF
J 0
(-7060 3000);
DISPLAY 0.510638 (-7060 3000);
PAINT SKYBLUE (-7060 3000);
FORCEPROP 1 LAST TOLERANCE 1%
J 0
(-7055 3200);
DISPLAY 0.510638 (-7055 3200);
PAINT SKYBLUE (-7055 3200);
FORCEPROP 1 LAST PATH I36
J 0
(-7050 3350);
DISPLAY 0.978723 (-7050 3350);
PAINT WHITE (-7050 3350);
DISPLAY INVISIBLE (-7050 3350);
FORCEPROP 2 LAST CDS_LIB pure_quanta
J 0
(-7100 3175);
DISPLAY INVISIBLE (-7100 3175);
FORCEPROP 1 LAST PART_NUMBER CS31002FB08
J 0
(-7060 3050);
DISPLAY 0.510638 (-7060 3050);
PAINT WHITE (-7060 3050);
DISPLAY INVISIBLE (-7060 3050);
FORCEPROP 1 LAST LOCATION R814
J 0
(-7055 3300);
DISPLAY 0.702128 (-7055 3300);
PAINT YELLOW (-7055 3300);
FORCEPROP 1 LASTPIN (-7100 3275) $PN 1
J 0
(-7095 3237);
DISPLAY 0.808511 (-7095 3237);
PAINT WHITE (-7095 3237);
FORCEPROP 1 LASTPIN (-7100 3075) $PN 2
J 0
(-7095 3085);
DISPLAY 0.808511 (-7095 3085);
PAINT WHITE (-7095 3085);
FORCEPROP 0 LAST $SEC 1
J 0
(-7050 3350);
DISPLAY 0.680851 (-7050 3350);
PAINT MONO (-7050 3350);
DISPLAY INVISIBLE (-7050 3350);
FORCEPROP 0 LAST CDS_SEC 1
J 0
(-7050 3350);
DISPLAY 0.680851 (-7050 3350);
DISPLAY INVISIBLE (-7050 3350);
FORCEADD Q_CAP..1
(-6925 2150);
FORCEPROP 1 LAST VALUE 470PF
J 0
(-6875 2175);
DISPLAY 0.510638 (-6875 2175);
PAINT SKYBLUE (-6875 2175);
FORCEPROP 1 LAST VOLTAGE 50V
J 0
(-6875 2125);
DISPLAY 0.510638 (-6875 2125);
PAINT SKYBLUE (-6875 2125);
FORCEPROP 1 LAST TOLERANCE 10%
J 0
(-6875 2075);
DISPLAY 0.510638 (-6875 2075);
PAINT SKYBLUE (-6875 2075);
FORCEPROP 1 LAST MATERIAL X7R
J 0
(-6875 2025);
DISPLAY 0.510638 (-6875 2025);
PAINT SKYBLUE (-6875 2025);
FORCEPROP 1 LAST PACK_TYPE 0402
J 0
(-6875 1975);
DISPLAY 0.510638 (-6875 1975);
PAINT SKYBLUE (-6875 1975);
FORCEPROP 1 LAST PATH I37
J 0
(-6875 2300);
DISPLAY 0.978723 (-6875 2300);
PAINT WHITE (-6875 2300);
DISPLAY INVISIBLE (-6875 2300);
FORCEPROP 1 LAST PART_NUMBER TMP_QCH14706KB18
J 0
(-6875 1925);
DISPLAY 0.510638 (-6875 1925);
PAINT WHITE (-6875 1925);
DISPLAY INVISIBLE (-6875 1925);
FORCEPROP 2 LAST CDS_LIB pure_quanta
J 0
(-6925 2150);
DISPLAY INVISIBLE (-6925 2150);
FORCEPROP 1 LAST LOCATION C324
J 0
(-6875 2225);
DISPLAY 0.702128 (-6875 2225);
PAINT YELLOW (-6875 2225);
FORCEPROP 1 LASTPIN (-6925 2250) $PN 1
J 0
(-6915 2230);
DISPLAY 0.808511 (-6915 2230);
PAINT WHITE (-6915 2230);
FORCEPROP 1 LASTPIN (-6925 2050) $PN 2
J 0
(-6915 2030);
DISPLAY 0.808511 (-6915 2030);
PAINT WHITE (-6915 2030);
FORCEPROP 2 LAST $SEC 1
J 0
(-6875 2350);
DISPLAY 0.680851 (-6875 2350);
PAINT MONO (-6875 2350);
DISPLAY INVISIBLE (-6875 2350);
FORCEPROP 0 LAST CDS_SEC 1
J 0
(-6875 2350);
DISPLAY 0.680851 (-6875 2350);
PAINT MONO (-6875 2350);
DISPLAY INVISIBLE (-6875 2350);
FORCEADD Q_CAP..1
(-6650 2150);
FORCEPROP 1 LAST VALUE 470PF
J 0
(-6600 2175);
DISPLAY 0.510638 (-6600 2175);
PAINT SKYBLUE (-6600 2175);
FORCEPROP 1 LAST PART_NUMBER TMP_QCH14706KB18
J 0
(-6600 1925);
DISPLAY 0.510638 (-6600 1925);
PAINT WHITE (-6600 1925);
FORCEPROP 1 LAST PACK_TYPE 0402
J 0
(-6600 1975);
DISPLAY 0.510638 (-6600 1975);
PAINT SKYBLUE (-6600 1975);
FORCEPROP 1 LAST MATERIAL X7R
J 0
(-6600 2025);
DISPLAY 0.510638 (-6600 2025);
PAINT SKYBLUE (-6600 2025);
FORCEPROP 1 LAST TOLERANCE 10%
J 0
(-6600 2075);
DISPLAY 0.510638 (-6600 2075);
PAINT SKYBLUE (-6600 2075);
FORCEPROP 1 LAST VOLTAGE 50V
J 0
(-6600 2125);
DISPLAY 0.510638 (-6600 2125);
PAINT SKYBLUE (-6600 2125);
FORCEPROP 1 LAST PATH I38
J 0
(-6600 2300);
DISPLAY 0.978723 (-6600 2300);
PAINT WHITE (-6600 2300);
DISPLAY INVISIBLE (-6600 2300);
FORCEPROP 2 LAST CDS_LIB pure_quanta
J 0
(-6650 2150);
DISPLAY INVISIBLE (-6650 2150);
FORCEPROP 1 LAST LOCATION C326
J 0
(-6600 2225);
DISPLAY 0.702128 (-6600 2225);
PAINT YELLOW (-6600 2225);
FORCEPROP 1 LASTPIN (-6650 2250) $PN 1
J 0
(-6640 2230);
DISPLAY 0.808511 (-6640 2230);
PAINT WHITE (-6640 2230);
FORCEPROP 1 LASTPIN (-6650 2050) $PN 2
J 0
(-6640 2030);
DISPLAY 0.808511 (-6640 2030);
PAINT WHITE (-6640 2030);
FORCEPROP 2 LAST $SEC 1
J 0
(-6600 2350);
DISPLAY 0.680851 (-6600 2350);
PAINT MONO (-6600 2350);
DISPLAY INVISIBLE (-6600 2350);
FORCEPROP 0 LAST CDS_SEC 1
J 0
(-6600 2350);
DISPLAY 0.680851 (-6600 2350);
PAINT MONO (-6600 2350);
DISPLAY INVISIBLE (-6600 2350);
FORCEADD UNIVERSAL_GND..1
(-7150 4775);
FORCEPROP 3 LASTPIN (-7150 4825) SIG_NAME GND\g
J 0
(-7140 4835);
DISPLAY 0.659574 (-7140 4835);
PAINT MONO (-7140 4835);
DISPLAY INVISIBLE (-7140 4835);
FORCEPROP 1 LAST HDL_POWER GND
J 1
(-7125 4700);
DISPLAY 0.702128 (-7125 4700);
PAINT GREEN (-7125 4700);
DISPLAY INVISIBLE (-7125 4700);
FORCEPROP 2 LAST CDS_LIB logical_power
J 0
(-7150 4775);
DISPLAY INVISIBLE (-7150 4775);
FORCEPROP 1 LAST PATH I4
J 0
(-7075 4775);
DISPLAY 0.872340 (-7075 4775);
PAINT AQUA (-7075 4775);
DISPLAY INVISIBLE (-7075 4775);
FORCEADD Q_RES..2
(-6800 3175);
FORCEPROP 1 LAST VALUE 10K
J 0
(-6755 3250);
DISPLAY 0.510638 (-6755 3250);
PAINT SKYBLUE (-6755 3250);
FORCEPROP 1 LAST PART_NUMBER CS31002FB08
J 0
(-6760 3050);
DISPLAY 0.510638 (-6760 3050);
PAINT WHITE (-6760 3050);
FORCEPROP 1 LAST PACK_TYPE 0402LF
J 0
(-6760 3000);
DISPLAY 0.510638 (-6760 3000);
PAINT SKYBLUE (-6760 3000);
FORCEPROP 1 LAST WATTAGE 1/16W
J 0
(-6760 3150);
DISPLAY 0.510638 (-6760 3150);
PAINT SKYBLUE (-6760 3150);
FORCEPROP 1 LAST TOLERANCE 1%
J 0
(-6755 3200);
DISPLAY 0.510638 (-6755 3200);
PAINT SKYBLUE (-6755 3200);
FORCEPROP 1 LAST MATERIAL CHIP
J 0
(-6760 3100);
DISPLAY 0.510638 (-6760 3100);
PAINT SKYBLUE (-6760 3100);
FORCEPROP 1 LAST PATH I40
J 0
(-6750 3350);
DISPLAY 0.978723 (-6750 3350);
PAINT WHITE (-6750 3350);
DISPLAY INVISIBLE (-6750 3350);
FORCEPROP 2 LAST CDS_LIB pure_quanta
J 0
(-6800 3175);
DISPLAY INVISIBLE (-6800 3175);
FORCEPROP 1 LAST LOCATION R815
J 0
(-6755 3300);
DISPLAY 0.702128 (-6755 3300);
PAINT YELLOW (-6755 3300);
FORCEPROP 1 LASTPIN (-6800 3275) $PN 1
J 0
(-6795 3237);
DISPLAY 0.808511 (-6795 3237);
PAINT WHITE (-6795 3237);
FORCEPROP 1 LASTPIN (-6800 3075) $PN 2
J 0
(-6795 3085);
DISPLAY 0.808511 (-6795 3085);
PAINT WHITE (-6795 3085);
FORCEPROP 0 LAST $SEC 1
J 0
(-6750 3350);
DISPLAY 0.680851 (-6750 3350);
PAINT MONO (-6750 3350);
DISPLAY INVISIBLE (-6750 3350);
FORCEPROP 0 LAST CDS_SEC 1
J 0
(-6750 3350);
DISPLAY 0.680851 (-6750 3350);
DISPLAY INVISIBLE (-6750 3350);
FORCEADD Q_CAP..1
(-5200 2150);
FORCEPROP 1 LAST VALUE 0.1UF
J 0
(-5150 2175);
DISPLAY 0.510638 (-5150 2175);
PAINT SKYBLUE (-5150 2175);
FORCEPROP 1 LAST MATERIAL X7R
J 0
(-5150 2025);
DISPLAY 0.510638 (-5150 2025);
PAINT SKYBLUE (-5150 2025);
FORCEPROP 1 LAST PACK_TYPE 0402
J 0
(-5150 1975);
DISPLAY 0.510638 (-5150 1975);
PAINT SKYBLUE (-5150 1975);
FORCEPROP 1 LAST TOLERANCE 10%
J 0
(-5150 2075);
DISPLAY 0.510638 (-5150 2075);
PAINT SKYBLUE (-5150 2075);
FORCEPROP 1 LAST VOLTAGE 25V
J 0
(-5150 2125);
DISPLAY 0.510638 (-5150 2125);
PAINT SKYBLUE (-5150 2125);
FORCEPROP 1 LAST PATH I43
J 0
(-5150 2300);
DISPLAY 0.978723 (-5150 2300);
PAINT WHITE (-5150 2300);
DISPLAY INVISIBLE (-5150 2300);
FORCEPROP 1 LAST PART_NUMBER CH4104K1B00
J 0
(-5150 1925);
DISPLAY 0.510638 (-5150 1925);
PAINT WHITE (-5150 1925);
DISPLAY INVISIBLE (-5150 1925);
FORCEPROP 2 LAST CDS_LIB pure_quanta
J 0
(-5200 2150);
DISPLAY INVISIBLE (-5200 2150);
FORCEPROP 1 LAST LOCATION C321
J 0
(-5150 2225);
DISPLAY 0.702128 (-5150 2225);
PAINT YELLOW (-5150 2225);
FORCEPROP 1 LASTPIN (-5200 2250) $PN 1
J 0
(-5190 2230);
DISPLAY 0.808511 (-5190 2230);
PAINT WHITE (-5190 2230);
FORCEPROP 1 LASTPIN (-5200 2050) $PN 2
J 0
(-5190 2030);
DISPLAY 0.808511 (-5190 2030);
PAINT WHITE (-5190 2030);
FORCEPROP 2 LAST $SEC 1
J 0
(-5150 2350);
DISPLAY 0.680851 (-5150 2350);
PAINT MONO (-5150 2350);
DISPLAY INVISIBLE (-5150 2350);
FORCEPROP 0 LAST CDS_SEC 1
J 0
(-5150 2350);
DISPLAY 0.680851 (-5150 2350);
PAINT MONO (-5150 2350);
DISPLAY INVISIBLE (-5150 2350);
FORCEADD Q_CAP..1
(-4975 2150);
FORCEPROP 1 LAST MATERIAL X7R
J 0
(-4925 2025);
DISPLAY 0.510638 (-4925 2025);
PAINT SKYBLUE (-4925 2025);
FORCEPROP 1 LAST TOLERANCE 10%
J 0
(-4925 2075);
DISPLAY 0.510638 (-4925 2075);
PAINT SKYBLUE (-4925 2075);
FORCEPROP 1 LAST PART_NUMBER CH4104K1B00
J 0
(-4925 1925);
DISPLAY 0.510638 (-4925 1925);
PAINT WHITE (-4925 1925);
FORCEPROP 1 LAST PACK_TYPE 0402
J 0
(-4925 1975);
DISPLAY 0.510638 (-4925 1975);
PAINT SKYBLUE (-4925 1975);
FORCEPROP 1 LAST VALUE 0.1UF
J 0
(-4925 2175);
DISPLAY 0.510638 (-4925 2175);
PAINT SKYBLUE (-4925 2175);
FORCEPROP 1 LAST VOLTAGE 25V
J 0
(-4925 2125);
DISPLAY 0.510638 (-4925 2125);
PAINT SKYBLUE (-4925 2125);
FORCEPROP 1 LAST PATH I45
J 0
(-4925 2300);
DISPLAY 0.978723 (-4925 2300);
PAINT WHITE (-4925 2300);
DISPLAY INVISIBLE (-4925 2300);
FORCEPROP 2 LAST CDS_LIB pure_quanta
J 0
(-4975 2150);
DISPLAY INVISIBLE (-4975 2150);
FORCEPROP 1 LAST LOCATION C197
J 0
(-4925 2225);
DISPLAY 0.702128 (-4925 2225);
PAINT YELLOW (-4925 2225);
FORCEPROP 1 LASTPIN (-4975 2250) $PN 1
J 0
(-4965 2230);
DISPLAY 0.808511 (-4965 2230);
PAINT WHITE (-4965 2230);
FORCEPROP 1 LASTPIN (-4975 2050) $PN 2
J 0
(-4965 2030);
DISPLAY 0.808511 (-4965 2030);
PAINT WHITE (-4965 2030);
FORCEPROP 2 LAST $SEC 1
J 0
(-4925 2350);
DISPLAY 0.680851 (-4925 2350);
PAINT MONO (-4925 2350);
DISPLAY INVISIBLE (-4925 2350);
FORCEPROP 0 LAST CDS_SEC 1
J 0
(-4925 2350);
DISPLAY 0.680851 (-4925 2350);
PAINT MONO (-4925 2350);
DISPLAY INVISIBLE (-4925 2350);
FORCEADD UNIVERSAL_GND..1
(-4975 1825);
FORCEPROP 3 LASTPIN (-4975 1875) SIG_NAME GND\g
J 0
(-4965 1885);
DISPLAY 0.659574 (-4965 1885);
PAINT MONO (-4965 1885);
DISPLAY INVISIBLE (-4965 1885);
FORCEPROP 1 LAST PATH I46
J 0
(-4900 1825);
DISPLAY 0.872340 (-4900 1825);
PAINT AQUA (-4900 1825);
DISPLAY INVISIBLE (-4900 1825);
FORCEPROP 1 LAST HDL_POWER GND
J 1
(-4950 1750);
DISPLAY 0.702128 (-4950 1750);
PAINT GREEN (-4950 1750);
DISPLAY INVISIBLE (-4950 1750);
FORCEPROP 2 LAST CDS_LIB logical_power
J 0
(-4975 1825);
DISPLAY INVISIBLE (-4975 1825);
FORCEADD UNIVERSAL_POWER..1
(-4975 3500);
FORCEPROP 3 LASTPIN (-4975 3450) SIG_NAME P5V_AUX\g
J 0
(-4965 3460);
DISPLAY 0.659574 (-4965 3460);
PAINT MONO (-4965 3460);
DISPLAY INVISIBLE (-4965 3460);
FORCEPROP 1 LAST HDL_POWER P5V_AUX
J 1
(-4975 3550);
DISPLAY 0.702128 (-4975 3550);
PAINT RED (-4975 3550);
FORCEPROP 1 LAST PATH I48
J 0
(-4925 3525);
DISPLAY 0.872340 (-4925 3525);
PAINT AQUA (-4925 3525);
DISPLAY INVISIBLE (-4925 3525);
FORCEPROP 2 LAST CDS_LIB logical_power
J 0
(-4975 3500);
DISPLAY INVISIBLE (-4975 3500);
FORCEADD UNIVERSAL_GND..1
(-6925 1825);
FORCEPROP 3 LASTPIN (-6925 1875) SIG_NAME GND\g
J 0
(-6915 1885);
DISPLAY 0.659574 (-6915 1885);
PAINT MONO (-6915 1885);
DISPLAY INVISIBLE (-6915 1885);
FORCEPROP 1 LAST PATH I49
J 0
(-6850 1825);
DISPLAY 0.872340 (-6850 1825);
PAINT AQUA (-6850 1825);
DISPLAY INVISIBLE (-6850 1825);
FORCEPROP 1 LAST HDL_POWER GND
J 1
(-6900 1750);
DISPLAY 0.702128 (-6900 1750);
PAINT GREEN (-6900 1750);
DISPLAY INVISIBLE (-6900 1750);
FORCEPROP 2 LAST CDS_LIB logical_power
J 0
(-6925 1825);
DISPLAY INVISIBLE (-6925 1825);
FORCEADD MC74VHC1G32DTT1G..1
(-6325 4975);
FORCEPROP 1 LAST MATERIAL IC
J 0
(-6720 5257);
DISPLAY 0.723404 (-6720 5257);
PAINT GREEN (-6720 5257);
FORCEPROP 2 LAST PART_TYPE SMLF
J 0
(-6725 5550);
DISPLAY 0.680851 (-6725 5550);
FORCEPROP 2 LAST VALUE MC74VHC1G32DTT1G
J 0
(-6725 5500);
DISPLAY 0.680851 (-6725 5500);
FORCEPROP 1 LAST PART_NUMBER AL001G32031
J 0
(-6720 5384);
DISPLAY 0.723404 (-6720 5384);
PAINT GREEN (-6720 5384);
FORCEPROP 1 LAST CDS_LMAN_SYM_OUTLINE -400,275,400,-275
J 0
(-6325 4975);
DISPLAY 0.468085 (-6325 4975);
PAINT GREEN (-6325 4975);
DISPLAY INVISIBLE (-6325 4975);
FORCEPROP 1 LAST NEEDS_NO_SIZE TRUE
J 0
(-6325 4975);
DISPLAY 0.723404 (-6325 4975);
PAINT GREEN (-6325 4975);
DISPLAY INVISIBLE (-6325 4975);
FORCEPROP 2 LAST CDS_LIB pure_quanta
J 0
(-6325 4975);
DISPLAY INVISIBLE (-6325 4975);
FORCEPROP 1 LAST PATH I5
J 0
(-6325 4975);
DISPLAY 0.723404 (-6325 4975);
PAINT GREEN (-6325 4975);
DISPLAY INVISIBLE (-6325 4975);
FORCEPROP 1 LAST $LOCATION U9
J 0
(-6745 5456);
DISPLAY 0.723404 (-6745 5456);
PAINT GREEN (-6745 5456);
FORCEPROP 0 LASTPIN (-6875 4800) $PN 3
J 2
(-6885 4810);
DISPLAY 0.680851 (-6885 4810);
PAINT MONO (-6885 4810);
FORCEPROP 0 LASTPIN (-6875 4950) $PN 2
J 2
(-6885 4960);
DISPLAY 0.680851 (-6885 4960);
PAINT MONO (-6885 4960);
FORCEPROP 0 LASTPIN (-6875 5150) $PN 1
J 2
(-6885 5160);
DISPLAY 0.680851 (-6885 5160);
PAINT MONO (-6885 5160);
FORCEPROP 0 LASTPIN (-5775 4800) $PN 4
J 0
(-5765 4810);
DISPLAY 0.680851 (-5765 4810);
PAINT MONO (-5765 4810);
FORCEPROP 0 LASTPIN (-5775 5150) $PN 5
J 0
(-5765 5160);
DISPLAY 0.680851 (-5765 5160);
PAINT MONO (-5765 5160);
FORCEPROP 0 LAST CDS_LOCATION U9
J 0
(-6725 5600);
DISPLAY 0.680851 (-6725 5600);
DISPLAY INVISIBLE (-6725 5600);
FORCEPROP 0 LAST $SEC 1
J 0
(-6725 5600);
DISPLAY 0.680851 (-6725 5600);
PAINT MONO (-6725 5600);
DISPLAY INVISIBLE (-6725 5600);
FORCEPROP 0 LAST CDS_SEC 1
J 0
(-6725 5600);
DISPLAY 0.680851 (-6725 5600);
DISPLAY INVISIBLE (-6725 5600);
FORCEADD Q_LED..1
R 2
(-1075 2450);
FORCEPROP 1 LAST PART_NUMBER BEBL0172Z00
J 2
(-975 2585);
DISPLAY 0.723404 (-975 2585);
PAINT GREEN (-975 2585);
FORCEPROP 2 LAST COLOR LED_BLUE
J 2
(-975 2775);
DISPLAY 0.680851 (-975 2775);
FORCEPROP 2 LAST PACK_TYPE SMLF
J 2
(-975 2675);
DISPLAY 0.680851 (-975 2675);
FORCEPROP 1 LAST MATERIAL IC
J 2
(-975 2530);
DISPLAY 0.723404 (-975 2530);
PAINT GREEN (-975 2530);
FORCEPROP 2 LAST MANUF_PN LTST-C281TBKT-5A
J 2
(-975 2725);
DISPLAY 0.680851 (-975 2725);
FORCEPROP 2 LAST CDS_LIB pure_quanta
J 2
(-1075 2450);
DISPLAY INVISIBLE (-1075 2450);
FORCEPROP 1 LAST PATH I50
J 2
(-1200 2530);
DISPLAY 0.723404 (-1200 2530);
PAINT GREEN (-1200 2530);
DISPLAY INVISIBLE (-1200 2530);
FORCEPROP 1 LAST NEEDS_NO_SIZE TRUE
J 2
(-1075 2450);
DISPLAY 0.468085 (-1075 2450);
PAINT GREEN (-1075 2450);
DISPLAY INVISIBLE (-1075 2450);
FORCEPROP 1 LAST $LOCATION D19
J 2
(-975 2635);
DISPLAY 0.723404 (-975 2635);
PAINT GREEN (-975 2635);
FORCEPROP 0 LASTPIN (-925 2450) $PN A
J 0
(-915 2460);
DISPLAY 0.680851 (-915 2460);
PAINT MONO (-915 2460);
FORCEPROP 0 LASTPIN (-1225 2450) $PN C
J 2
(-1235 2460);
DISPLAY 0.680851 (-1235 2460);
PAINT MONO (-1235 2460);
FORCEPROP 0 LAST CDS_LOCATION D19
J 0
(-975 2825);
DISPLAY 0.680851 (-975 2825);
DISPLAY INVISIBLE (-975 2825);
FORCEPROP 0 LAST $SEC 1
J 0
(-975 2825);
DISPLAY 0.680851 (-975 2825);
PAINT MONO (-975 2825);
DISPLAY INVISIBLE (-975 2825);
FORCEPROP 0 LAST CDS_SEC 1
J 0
(-975 2825);
DISPLAY 0.680851 (-975 2825);
DISPLAY INVISIBLE (-975 2825);
FORCEADD Q_LED..1
R 2
(-1075 2925);
FORCEPROP 2 LAST COLOR LED_BLUE
J 2
(-975 3250);
DISPLAY 0.680851 (-975 3250);
FORCEPROP 2 LAST MANUF_PN LTST-C281TBKT-5A
J 2
(-975 3200);
DISPLAY 0.680851 (-975 3200);
FORCEPROP 2 LAST PACK_TYPE SMLF
J 2
(-975 3150);
DISPLAY 0.680851 (-975 3150);
FORCEPROP 1 LAST MATERIAL IC
J 2
(-975 3005);
DISPLAY 0.723404 (-975 3005);
PAINT GREEN (-975 3005);
FORCEPROP 1 LAST PART_NUMBER BEBL0172Z00
J 2
(-975 3060);
DISPLAY 0.723404 (-975 3060);
PAINT GREEN (-975 3060);
FORCEPROP 1 LAST NEEDS_NO_SIZE TRUE
J 2
(-1075 2925);
DISPLAY 0.468085 (-1075 2925);
PAINT GREEN (-1075 2925);
DISPLAY INVISIBLE (-1075 2925);
FORCEPROP 1 LAST PATH I51
J 2
(-1200 3005);
DISPLAY 0.723404 (-1200 3005);
PAINT GREEN (-1200 3005);
DISPLAY INVISIBLE (-1200 3005);
FORCEPROP 2 LAST CDS_LIB pure_quanta
J 0
(-1075 2925);
DISPLAY INVISIBLE (-1075 2925);
FORCEPROP 1 LAST $LOCATION D18
J 2
(-975 3110);
DISPLAY 0.723404 (-975 3110);
PAINT GREEN (-975 3110);
FORCEPROP 0 LASTPIN (-925 2925) $PN A
J 0
(-915 2935);
DISPLAY 0.680851 (-915 2935);
PAINT MONO (-915 2935);
FORCEPROP 0 LASTPIN (-1225 2925) $PN C
J 2
(-1235 2935);
DISPLAY 0.680851 (-1235 2935);
PAINT MONO (-1235 2935);
FORCEPROP 0 LAST CDS_LOCATION D18
J 0
(-975 3300);
DISPLAY 0.680851 (-975 3300);
DISPLAY INVISIBLE (-975 3300);
FORCEPROP 0 LAST $SEC 1
J 0
(-975 3300);
DISPLAY 0.680851 (-975 3300);
PAINT MONO (-975 3300);
DISPLAY INVISIBLE (-975 3300);
FORCEPROP 0 LAST CDS_SEC 1
J 0
(-975 3300);
DISPLAY 0.680851 (-975 3300);
DISPLAY INVISIBLE (-975 3300);
FORCEADD VCCAUX15..1
(-800 3525);
FORCEPROP 3 LASTPIN (-800 3475) SIG_NAME P3V3_AUX\g
J 0
(-790 3485);
DISPLAY 0.659574 (-790 3485);
PAINT MONO (-790 3485);
DISPLAY INVISIBLE (-790 3485);
FORCEPROP 1 LAST HDL_POWER P3V3_AUX
J 1
(-800 3575);
DISPLAY 0.702128 (-800 3575);
PAINT GREEN (-800 3575);
FORCEPROP 2 LAST CDS_LIB logical_power
J 0
(-800 3525);
DISPLAY INVISIBLE (-800 3525);
FORCEPROP 1 LAST PATH I52
J 0
(-750 3550);
DISPLAY 0.872340 (-750 3550);
PAINT AQUA (-750 3550);
DISPLAY INVISIBLE (-750 3550);
FORCEADD OFFPAGE..1
(-3100 2925);
FORCEPROP 2 LAST $XR1 30 
J 0
(-3441 2925);
DISPLAY 0.638298 (-3441 2925);
PAINT MONO (-3441 2925);
FORCEPROP 2 LAST $XR0 36 
J 0
(-3351 2925);
DISPLAY 0.638298 (-3351 2925);
PAINT MONO (-3351 2925);
FORCEPROP 1 LAST COMMENT_BODY TRUE
J 0
(-2975 2825);
DISPLAY 0.872340 (-2975 2825);
PAINT PEACH (-2975 2825);
DISPLAY INVISIBLE (-2975 2825);
FORCEPROP 1 LAST OFFPAGE TRUE
J 0
(-2775 2800);
DISPLAY 0.872340 (-2775 2800);
PAINT GREEN (-2775 2800);
DISPLAY INVISIBLE (-2775 2800);
FORCEPROP 2 LAST PATH I55
J 0
(-3050 3000);
DISPLAY 0.680851 (-3050 3000);
DISPLAY INVISIBLE (-3050 3000);
FORCEPROP 2 LAST CDS_LIB standard
J 0
(-3100 2925);
DISPLAY INVISIBLE (-3100 2925);
FORCEADD OFFPAGE..1
(-3100 2450);
FORCEPROP 2 LAST $XR0 36 
J 0
(-3351 2450);
DISPLAY 0.638298 (-3351 2450);
PAINT MONO (-3351 2450);
FORCEPROP 2 LAST $XR1 30 
J 0
(-3441 2450);
DISPLAY 0.638298 (-3441 2450);
PAINT MONO (-3441 2450);
FORCEPROP 1 LAST COMMENT_BODY TRUE
J 0
(-2975 2350);
DISPLAY 0.872340 (-2975 2350);
PAINT PEACH (-2975 2350);
DISPLAY INVISIBLE (-2975 2350);
FORCEPROP 1 LAST OFFPAGE TRUE
J 0
(-2775 2325);
DISPLAY 0.872340 (-2775 2325);
PAINT GREEN (-2775 2325);
DISPLAY INVISIBLE (-2775 2325);
FORCEPROP 2 LAST PATH I56
J 0
(-3050 2525);
DISPLAY 0.680851 (-3050 2525);
DISPLAY INVISIBLE (-3050 2525);
FORCEPROP 2 LAST CDS_LIB standard
J 0
(-3100 2450);
DISPLAY INVISIBLE (-3100 2450);
FORCEADD UNIVERSAL_POWER..1
(-7100 3500);
FORCEPROP 3 LASTPIN (-7100 3450) SIG_NAME P5V_AUX\g
J 0
(-7090 3460);
DISPLAY 0.659574 (-7090 3460);
PAINT MONO (-7090 3460);
DISPLAY INVISIBLE (-7090 3460);
FORCEPROP 1 LAST HDL_POWER P5V_AUX
J 1
(-7100 3550);
DISPLAY 0.702128 (-7100 3550);
PAINT RED (-7100 3550);
FORCEPROP 1 LAST PATH I58
J 0
(-7050 3525);
DISPLAY 0.872340 (-7050 3525);
PAINT AQUA (-7050 3525);
DISPLAY INVISIBLE (-7050 3525);
FORCEPROP 2 LAST CDS_LIB logical_power
J 0
(-7100 3500);
DISPLAY INVISIBLE (-7100 3500);
FORCEADD Q_RES..1
R 1
(-5200 3175);
FORCEPROP 1 LAST WATTAGE 1/16W
R 1
J 2
(-5125 3475);
DISPLAY 0.723404 (-5125 3475);
PAINT SKYBLUE (-5125 3475);
FORCEPROP 1 LAST VALUE 220
R 1
J 2
(-5125 2950);
DISPLAY 0.723404 (-5125 2950);
PAINT SKYBLUE (-5125 2950);
FORCEPROP 1 LAST TOLERANCE 1%
R 1
J 0
(-5125 2975);
DISPLAY 0.723404 (-5125 2975);
PAINT SKYBLUE (-5125 2975);
FORCEPROP 1 LAST PACK_TYPE 0402LF
R 1
J 0
(-5125 3075);
DISPLAY 0.723404 (-5125 3075);
PAINT SKYBLUE (-5125 3075);
FORCEPROP 1 LAST PART_NUMBER CS12202FB04
R 1
J 0
(-5075 2850);
DISPLAY 0.723404 (-5075 2850);
PAINT WHITE (-5075 2850);
FORCEPROP 1 LAST MATERIAL CHIP
R 1
J 0
(-5025 2850);
DISPLAY 0.723404 (-5025 2850);
PAINT SKYBLUE (-5025 2850);
FORCEPROP 2 LAST CDS_LIB pure_quanta
R 1
J 0
(-5200 3175);
DISPLAY INVISIBLE (-5200 3175);
FORCEPROP 1 LAST PATH I59
R 1
J 0
(-5350 3125);
DISPLAY 0.978723 (-5350 3125);
PAINT WHITE (-5350 3125);
DISPLAY INVISIBLE (-5350 3125);
FORCEPROP 1 LAST LOCATION R568
R 1
J 0
(-5200 2925);
DISPLAY 0.723404 (-5200 2925);
PAINT YELLOW (-5200 2925);
FORCEPROP 1 LASTPIN (-5200 3075) $PN 1
R 1
J 0
(-5212 3087);
DISPLAY 0.723404 (-5212 3087);
PAINT MONO (-5212 3087);
FORCEPROP 1 LASTPIN (-5200 3275) $PN 2
R 1
J 0
(-5212 3237);
DISPLAY 0.723404 (-5212 3237);
PAINT MONO (-5212 3237);
FORCEPROP 2 LAST $SEC 1
R 1
J 0
(-5400 3125);
DISPLAY 0.680851 (-5400 3125);
PAINT MONO (-5400 3125);
DISPLAY INVISIBLE (-5400 3125);
FORCEPROP 0 LAST CDS_SEC 1
R 1
J 0
(-5400 3125);
DISPLAY 0.680851 (-5400 3125);
PAINT MONO (-5400 3125);
DISPLAY INVISIBLE (-5400 3125);
FORCEADD MOSFET_NCH_DUAL..1
(-5125 4850);
FORCEPROP 2 LAST VALUE PJT138K
J 0
(-4950 4875);
DISPLAY 0.680851 (-4950 4875);
FORCEPROP 1 LAST PART_NUMBER BAM138K0003
J 0
(-4974 4764);
DISPLAY 0.723404 (-4974 4764);
PAINT GREEN (-4974 4764);
FORCEPROP 1 LAST MATERIAL IC
J 0
(-4974 4699);
DISPLAY 0.723404 (-4974 4699);
PAINT GREEN (-4974 4699);
FORCEPROP 2 LAST PART_TYPE SMLF
J 0
(-4950 4925);
DISPLAY 0.680851 (-4950 4925);
FORCEPROP 1 LAST PATH I6
J 0
(-5125 4850);
DISPLAY 0.723404 (-5125 4850);
PAINT GREEN (-5125 4850);
DISPLAY INVISIBLE (-5125 4850);
FORCEPROP 2 LAST CDS_LIB pure_quanta
J 0
(-5125 4850);
DISPLAY INVISIBLE (-5125 4850);
FORCEPROP 1 LAST NEEDS_NO_SIZE TRUE
J 0
(-5125 4849);
DISPLAY 0.468085 (-5125 4849);
PAINT GREEN (-5125 4849);
DISPLAY INVISIBLE (-5125 4849);
FORCEPROP 1 LAST CDS_LMAN_SYM_OUTLINE -150,150,150,-150
J 0
(-5125 4850);
DISPLAY 0.468085 (-5125 4850);
PAINT GREEN (-5125 4850);
DISPLAY INVISIBLE (-5125 4850);
FORCEPROP 1 LAST $LOCATION Q9
J 0
(-4974 4824);
DISPLAY 0.723404 (-4974 4824);
PAINT GREEN (-4974 4824);
FORCEPROP 0 LASTPIN (-5075 5050) $PN 6
R 1
J 0
(-5085 5060);
DISPLAY 0.680851 (-5085 5060);
PAINT MONO (-5085 5060);
FORCEPROP 0 LASTPIN (-5325 4800) $PN 2
J 2
(-5335 4810);
DISPLAY 0.680851 (-5335 4810);
PAINT MONO (-5335 4810);
FORCEPROP 0 LASTPIN (-5075 4650) $PN 1
R 1
J 2
(-5085 4640);
DISPLAY 0.680851 (-5085 4640);
PAINT MONO (-5085 4640);
FORCEPROP 0 LAST CDS_LOCATION Q9
J 0
(-4950 4975);
DISPLAY 0.680851 (-4950 4975);
DISPLAY INVISIBLE (-4950 4975);
FORCEPROP 0 LAST $SEC 1
J 0
(-4950 4975);
DISPLAY 0.680851 (-4950 4975);
PAINT MONO (-4950 4975);
DISPLAY INVISIBLE (-4950 4975);
FORCEPROP 0 LAST CDS_SEC 1
J 0
(-4950 4975);
DISPLAY 0.680851 (-4950 4975);
DISPLAY INVISIBLE (-4950 4975);
FORCEADD Q_RES..1
R 1
(-4975 3175);
FORCEPROP 1 LAST VALUE 220
R 1
J 2
(-4900 2950);
DISPLAY 0.723404 (-4900 2950);
PAINT SKYBLUE (-4900 2950);
FORCEPROP 1 LAST WATTAGE 1/16W
R 1
J 2
(-4900 3475);
DISPLAY 0.723404 (-4900 3475);
PAINT SKYBLUE (-4900 3475);
FORCEPROP 1 LAST MATERIAL CHIP
R 1
J 0
(-4800 2850);
DISPLAY 0.723404 (-4800 2850);
PAINT SKYBLUE (-4800 2850);
FORCEPROP 1 LAST PACK_TYPE 0402LF
R 1
J 0
(-4900 3075);
DISPLAY 0.723404 (-4900 3075);
PAINT SKYBLUE (-4900 3075);
FORCEPROP 1 LAST PART_NUMBER CS12202FB04
R 1
J 0
(-4850 2850);
DISPLAY 0.723404 (-4850 2850);
PAINT WHITE (-4850 2850);
FORCEPROP 1 LAST TOLERANCE 1%
R 1
J 0
(-4900 2975);
DISPLAY 0.723404 (-4900 2975);
PAINT SKYBLUE (-4900 2975);
FORCEPROP 2 LAST CDS_LIB pure_quanta
J 0
(-4975 3175);
DISPLAY INVISIBLE (-4975 3175);
FORCEPROP 1 LAST PATH I60
R 1
J 0
(-5125 3125);
DISPLAY 0.978723 (-5125 3125);
PAINT WHITE (-5125 3125);
DISPLAY INVISIBLE (-5125 3125);
FORCEPROP 1 LAST LOCATION R569
R 1
J 0
(-4975 2925);
DISPLAY 0.723404 (-4975 2925);
PAINT YELLOW (-4975 2925);
FORCEPROP 1 LASTPIN (-4975 3075) $PN 1
R 1
J 0
(-4987 3087);
DISPLAY 0.787234 (-4987 3087);
PAINT MONO (-4987 3087);
FORCEPROP 1 LASTPIN (-4975 3275) $PN 2
R 1
J 0
(-4987 3237);
DISPLAY 0.787234 (-4987 3237);
PAINT MONO (-4987 3237);
FORCEPROP 0 LAST $SEC 1
R 1
J 0
(-4950 3300);
DISPLAY 0.680851 (-4950 3300);
PAINT MONO (-4950 3300);
DISPLAY INVISIBLE (-4950 3300);
FORCEPROP 0 LAST CDS_SEC 1
R 1
J 0
(-4950 3300);
DISPLAY 0.680851 (-4950 3300);
DISPLAY INVISIBLE (-4950 3300);
FORCEADD UNIVERSAL_GND..1
(-5075 4500);
FORCEPROP 3 LASTPIN (-5075 4550) SIG_NAME GND\g
J 0
(-5065 4560);
DISPLAY 0.659574 (-5065 4560);
PAINT MONO (-5065 4560);
DISPLAY INVISIBLE (-5065 4560);
FORCEPROP 2 LAST CDS_LIB logical_power
J 0
(-5075 4500);
DISPLAY INVISIBLE (-5075 4500);
FORCEPROP 1 LAST PATH I7
J 0
(-5000 4500);
DISPLAY 0.872340 (-5000 4500);
PAINT AQUA (-5000 4500);
DISPLAY INVISIBLE (-5000 4500);
FORCEPROP 1 LAST HDL_POWER GND
J 1
(-5050 4425);
DISPLAY 0.702128 (-5050 4425);
PAINT GREEN (-5050 4425);
DISPLAY INVISIBLE (-5050 4425);
FORCEADD Q_CAP..1
R 2
(-5900 5625);
FORCEPROP 1 LAST PART_NUMBER CH4104K1B00
J 2
(-5950 5400);
DISPLAY 0.510638 (-5950 5400);
PAINT WHITE (-5950 5400);
FORCEPROP 1 LAST PACK_TYPE 0402
J 2
(-5950 5450);
DISPLAY 0.510638 (-5950 5450);
PAINT SKYBLUE (-5950 5450);
FORCEPROP 1 LAST MATERIAL X7R
J 2
(-5950 5500);
DISPLAY 0.510638 (-5950 5500);
PAINT SKYBLUE (-5950 5500);
FORCEPROP 1 LAST VOLTAGE 25V
J 2
(-5950 5600);
DISPLAY 0.510638 (-5950 5600);
PAINT SKYBLUE (-5950 5600);
FORCEPROP 1 LAST VALUE 0.1UF
J 2
(-5950 5650);
DISPLAY 0.510638 (-5950 5650);
PAINT SKYBLUE (-5950 5650);
FORCEPROP 1 LAST TOLERANCE 10%
J 2
(-5950 5550);
DISPLAY 0.510638 (-5950 5550);
PAINT SKYBLUE (-5950 5550);
FORCEPROP 1 LAST PATH I75
J 2
(-5950 5775);
DISPLAY 0.978723 (-5950 5775);
PAINT WHITE (-5950 5775);
DISPLAY INVISIBLE (-5950 5775);
FORCEPROP 2 LAST CDS_LIB pure_quanta
J 0
(-5900 5625);
DISPLAY INVISIBLE (-5900 5625);
FORCEPROP 1 LAST $LOCATION C276
J 2
(-5950 5725);
DISPLAY 0.638298 (-5950 5725);
FORCEPROP 1 LASTPIN (-5900 5725) $PN 1
J 2
(-5910 5705);
DISPLAY 0.787234 (-5910 5705);
PAINT MONO (-5910 5705);
FORCEPROP 1 LASTPIN (-5900 5525) $PN 2
J 2
(-5910 5505);
DISPLAY 0.787234 (-5910 5505);
PAINT MONO (-5910 5505);
FORCEPROP 0 LAST CDS_LOCATION C276
J 0
(-5950 5775);
DISPLAY 0.680851 (-5950 5775);
DISPLAY INVISIBLE (-5950 5775);
FORCEPROP 0 LAST $SEC 1
J 0
(-5950 5775);
DISPLAY 0.680851 (-5950 5775);
PAINT MONO (-5950 5775);
DISPLAY INVISIBLE (-5950 5775);
FORCEPROP 0 LAST CDS_SEC 1
J 0
(-5950 5775);
DISPLAY 0.680851 (-5950 5775);
DISPLAY INVISIBLE (-5950 5775);
FORCEADD Q_RES..1
R 1
(-3200 5550);
FORCEPROP 1 LAST MATERIAL CHIP
R 1
J 0
(-3025 5225);
DISPLAY 0.723404 (-3025 5225);
PAINT SKYBLUE (-3025 5225);
FORCEPROP 1 LAST VALUE 220
R 1
J 2
(-3125 5325);
DISPLAY 0.723404 (-3125 5325);
PAINT SKYBLUE (-3125 5325);
FORCEPROP 1 LAST TOLERANCE 1%
R 1
J 0
(-3125 5350);
DISPLAY 0.723404 (-3125 5350);
PAINT SKYBLUE (-3125 5350);
FORCEPROP 1 LAST WATTAGE 1/16W
R 1
J 2
(-3125 5850);
DISPLAY 0.723404 (-3125 5850);
PAINT SKYBLUE (-3125 5850);
FORCEPROP 1 LAST PART_NUMBER CS12202FB04
R 1
J 0
(-3075 5225);
DISPLAY 0.723404 (-3075 5225);
PAINT WHITE (-3075 5225);
FORCEPROP 1 LAST PACK_TYPE 0402LF
R 1
J 0
(-3125 5450);
DISPLAY 0.723404 (-3125 5450);
PAINT SKYBLUE (-3125 5450);
FORCEPROP 2 LAST CDS_LIB pure_quanta
J 0
(-3200 5550);
DISPLAY INVISIBLE (-3200 5550);
FORCEPROP 1 LAST PATH I79
R 1
J 0
(-3350 5500);
DISPLAY 0.978723 (-3350 5500);
PAINT WHITE (-3350 5500);
DISPLAY INVISIBLE (-3350 5500);
FORCEPROP 1 LAST $LOCATION R43
R 1
J 0
(-3225 5275);
DISPLAY 0.723404 (-3225 5275);
PAINT YELLOW (-3225 5275);
FORCEPROP 1 LASTPIN (-3200 5450) $PN 1
R 1
J 0
(-3212 5462);
DISPLAY 0.787234 (-3212 5462);
PAINT MONO (-3212 5462);
FORCEPROP 1 LASTPIN (-3200 5650) $PN 2
R 1
J 0
(-3212 5612);
DISPLAY 0.787234 (-3212 5612);
PAINT MONO (-3212 5612);
FORCEPROP 0 LAST CDS_LOCATION R43
R 1
J 0
(-3175 5675);
DISPLAY 0.680851 (-3175 5675);
DISPLAY INVISIBLE (-3175 5675);
FORCEPROP 0 LAST $SEC 1
R 1
J 0
(-3175 5675);
DISPLAY 0.680851 (-3175 5675);
PAINT MONO (-3175 5675);
DISPLAY INVISIBLE (-3175 5675);
FORCEPROP 0 LAST CDS_SEC 1
R 1
J 0
(-3175 5675);
DISPLAY 0.680851 (-3175 5675);
DISPLAY INVISIBLE (-3175 5675);
FORCEADD Q_RES..2
(-7150 4975);
FORCEPROP 1 LAST PACK_TYPE 0402LF
J 0
(-7110 4800);
DISPLAY 0.510638 (-7110 4800);
PAINT SKYBLUE (-7110 4800);
FORCEPROP 1 LAST TOLERANCE 1%
J 0
(-7105 5000);
DISPLAY 0.510638 (-7105 5000);
PAINT SKYBLUE (-7105 5000);
FORCEPROP 1 LAST WATTAGE 1/16W
J 0
(-7110 4950);
DISPLAY 0.510638 (-7110 4950);
PAINT SKYBLUE (-7110 4950);
FORCEPROP 1 LAST MATERIAL CHIP
J 0
(-7110 4900);
DISPLAY 0.510638 (-7110 4900);
PAINT SKYBLUE (-7110 4900);
FORCEPROP 1 LAST VALUE 10K
J 0
(-7105 5050);
DISPLAY 0.510638 (-7105 5050);
PAINT SKYBLUE (-7105 5050);
FORCEPROP 2 LAST CDS_LIB pure_quanta
J 0
(-7150 4975);
DISPLAY INVISIBLE (-7150 4975);
FORCEPROP 1 LAST PART_NUMBER CS31002FB08
J 0
(-7110 4850);
DISPLAY 0.510638 (-7110 4850);
PAINT WHITE (-7110 4850);
DISPLAY INVISIBLE (-7110 4850);
FORCEPROP 1 LAST PATH I8
J 0
(-7100 5150);
DISPLAY 0.978723 (-7100 5150);
PAINT WHITE (-7100 5150);
DISPLAY INVISIBLE (-7100 5150);
FORCEPROP 1 LAST $LOCATION R306
J 0
(-7105 5100);
DISPLAY 0.702128 (-7105 5100);
PAINT YELLOW (-7105 5100);
FORCEPROP 1 LASTPIN (-7150 5075) $PN 1
J 0
(-7145 5037);
DISPLAY 0.787234 (-7145 5037);
PAINT MONO (-7145 5037);
FORCEPROP 1 LASTPIN (-7150 4875) $PN 2
J 0
(-7145 4885);
DISPLAY 0.787234 (-7145 4885);
PAINT MONO (-7145 4885);
FORCEPROP 0 LAST CDS_LOCATION R306
J 0
(-7100 5150);
DISPLAY 0.680851 (-7100 5150);
DISPLAY INVISIBLE (-7100 5150);
FORCEPROP 0 LAST $SEC 1
J 0
(-7100 5150);
DISPLAY 0.680851 (-7100 5150);
PAINT MONO (-7100 5150);
DISPLAY INVISIBLE (-7100 5150);
FORCEPROP 0 LAST CDS_SEC 1
J 0
(-7100 5150);
DISPLAY 0.680851 (-7100 5150);
DISPLAY INVISIBLE (-7100 5150);
FORCEADD Q_RES..1
(-2275 2925);
FORCEPROP 1 LAST PACK_TYPE 0402LF
J 0
(-2000 2825);
DISPLAY 0.638298 (-2000 2825);
FORCEPROP 1 LAST WATTAGE 1/16W
J 2
(-2275 2825);
DISPLAY 0.638298 (-2275 2825);
FORCEPROP 1 LAST MATERIAL CHIP
J 0
(-2250 2825);
DISPLAY 0.638298 (-2250 2825);
FORCEPROP 1 LAST VALUE 75
J 2
(-2275 2875);
DISPLAY 0.638298 (-2275 2875);
FORCEPROP 1 LAST TOLERANCE 1%
J 0
(-2250 2875);
DISPLAY 0.638298 (-2250 2875);
FORCEPROP 1 LAST PART_NUMBER CS07502FB04
J 0
(-2325 3025);
DISPLAY 0.638298 (-2325 3025);
FORCEPROP 1 LAST PATH I88
J 0
(-2325 3075);
DISPLAY 0.978723 (-2325 3075);
PAINT WHITE (-2325 3075);
DISPLAY INVISIBLE (-2325 3075);
FORCEPROP 2 LAST CDS_LIB pure_quanta
J 0
(-2275 2925);
DISPLAY INVISIBLE (-2275 2925);
FORCEPROP 1 LAST LOCATION R283
J 0
(-2325 2975);
DISPLAY 0.808511 (-2325 2975);
FORCEPROP 1 LASTPIN (-2375 2925) $PN 1
J 0
(-2363 2937);
DISPLAY 0.787234 (-2363 2937);
PAINT MONO (-2363 2937);
FORCEPROP 1 LASTPIN (-2175 2925) $PN 2
J 0
(-2213 2937);
DISPLAY 0.787234 (-2213 2937);
PAINT MONO (-2213 2937);
FORCEPROP 0 LAST $SEC 1
J 0
(-2325 3075);
DISPLAY 0.680851 (-2325 3075);
PAINT MONO (-2325 3075);
DISPLAY INVISIBLE (-2325 3075);
FORCEPROP 0 LAST CDS_SEC 1
J 0
(-2325 3075);
DISPLAY 0.680851 (-2325 3075);
DISPLAY INVISIBLE (-2325 3075);
FORCEADD Q_RES..1
(-2275 2450);
FORCEPROP 1 LAST TOLERANCE 1%
J 0
(-2250 2400);
DISPLAY 0.638298 (-2250 2400);
FORCEPROP 1 LAST VALUE 75
J 2
(-2275 2400);
DISPLAY 0.638298 (-2275 2400);
FORCEPROP 1 LAST WATTAGE 1/16W
J 2
(-2275 2350);
DISPLAY 0.638298 (-2275 2350);
FORCEPROP 1 LAST PART_NUMBER CS07502FB04
J 0
(-2325 2550);
DISPLAY 0.638298 (-2325 2550);
FORCEPROP 1 LAST PACK_TYPE 0402LF
J 0
(-2000 2350);
DISPLAY 0.638298 (-2000 2350);
FORCEPROP 1 LAST MATERIAL CHIP
J 0
(-2250 2350);
DISPLAY 0.638298 (-2250 2350);
FORCEPROP 1 LAST PATH I89
J 0
(-2325 2600);
DISPLAY 0.978723 (-2325 2600);
PAINT WHITE (-2325 2600);
DISPLAY INVISIBLE (-2325 2600);
FORCEPROP 2 LAST CDS_LIB pure_quanta
J 0
(-2275 2450);
DISPLAY INVISIBLE (-2275 2450);
FORCEPROP 1 LAST LOCATION R284
J 0
(-2325 2500);
DISPLAY 0.787234 (-2325 2500);
FORCEPROP 1 LASTPIN (-2375 2450) $PN 1
J 0
(-2363 2462);
DISPLAY 0.787234 (-2363 2462);
PAINT MONO (-2363 2462);
FORCEPROP 1 LASTPIN (-2175 2450) $PN 2
J 0
(-2213 2462);
DISPLAY 0.787234 (-2213 2462);
PAINT MONO (-2213 2462);
FORCEPROP 0 LAST $SEC 1
J 0
(-2325 2600);
DISPLAY 0.680851 (-2325 2600);
PAINT MONO (-2325 2600);
DISPLAY INVISIBLE (-2325 2600);
FORCEPROP 0 LAST CDS_SEC 1
J 0
(-2325 2600);
DISPLAY 0.680851 (-2325 2600);
DISPLAY INVISIBLE (-2325 2600);
FORCEADD OFFPAGE..1
(-8725 5100);
FORCEPROP 2 LAST $XR0 13 
J 0
(-8976 5100);
DISPLAY 0.638298 (-8976 5100);
PAINT MONO (-8976 5100);
FORCEPROP 2 LAST $XR1 42 
J 0
(-9066 5100);
DISPLAY 0.638298 (-9066 5100);
PAINT MONO (-9066 5100);
FORCEPROP 2 LAST CDS_LIB standard
J 0
(-8725 5100);
DISPLAY INVISIBLE (-8725 5100);
FORCEPROP 1 LAST COMMENT_BODY TRUE
J 0
(-8600 5000);
DISPLAY 0.872340 (-8600 5000);
PAINT PEACH (-8600 5000);
DISPLAY INVISIBLE (-8600 5000);
FORCEPROP 1 LAST OFFPAGE TRUE
J 0
(-8400 4975);
DISPLAY 0.872340 (-8400 4975);
PAINT GREEN (-8400 4975);
DISPLAY INVISIBLE (-8400 4975);
FORCEPROP 2 LAST PATH I9
J 0
(-8975 5150);
DISPLAY 0.680851 (-8975 5150);
DISPLAY INVISIBLE (-8975 5150);
FORCEADD Q_RES..1
(-7775 4575);
FORCEPROP 1 LAST VALUE 33.2
J 0
(-7725 4575);
DISPLAY 0.510638 (-7725 4575);
PAINT SKYBLUE (-7725 4575);
FORCEPROP 1 LAST MATERIAL CHIP
J 0
(-7600 4575);
DISPLAY 0.510638 (-7600 4575);
PAINT SKYBLUE (-7600 4575);
FORCEPROP 2 LAST CDS_LIB pure_quanta
J 0
(-7775 4575);
DISPLAY INVISIBLE (-7775 4575);
FORCEPROP 1 LAST PATH I92
J 0
(-7825 4725);
DISPLAY 0.978723 (-7825 4725);
PAINT WHITE (-7825 4725);
DISPLAY INVISIBLE (-7825 4725);
FORCEPROP 1 LAST WATTAGE 1/16W
J 2
(-7800 4425);
DISPLAY 0.510638 (-7800 4425);
PAINT SKYBLUE (-7800 4425);
DISPLAY INVISIBLE (-7800 4425);
FORCEPROP 1 LAST PACK_TYPE 0402LF
J 0
(-7525 4425);
DISPLAY 0.510638 (-7525 4425);
PAINT SKYBLUE (-7525 4425);
DISPLAY INVISIBLE (-7525 4425);
FORCEPROP 1 LAST PART_NUMBER CS03322FB03
J 0
(-7650 4625);
DISPLAY 0.510638 (-7650 4625);
PAINT WHITE (-7650 4625);
DISPLAY INVISIBLE (-7650 4625);
FORCEPROP 1 LAST TOLERANCE 1%
J 0
(-7650 4575);
DISPLAY 0.510638 (-7650 4575);
PAINT SKYBLUE (-7650 4575);
DISPLAY INVISIBLE (-7650 4575);
FORCEPROP 1 LAST $LOCATION R390
J 0
(-7950 4575);
DISPLAY 0.702128 (-7950 4575);
PAINT YELLOW (-7950 4575);
FORCEPROP 1 LASTPIN (-7875 4575) $PN 1
J 0
(-7863 4587);
DISPLAY 0.787234 (-7863 4587);
PAINT MONO (-7863 4587);
FORCEPROP 1 LASTPIN (-7675 4575) $PN 2
J 0
(-7713 4587);
DISPLAY 0.787234 (-7713 4587);
PAINT MONO (-7713 4587);
FORCEPROP 0 LAST CDS_LOCATION R390
J 0
(-7950 4625);
DISPLAY 0.680851 (-7950 4625);
DISPLAY INVISIBLE (-7950 4625);
FORCEPROP 0 LAST $SEC 1
J 0
(-7950 4625);
DISPLAY 0.680851 (-7950 4625);
PAINT MONO (-7950 4625);
DISPLAY INVISIBLE (-7950 4625);
FORCEPROP 0 LAST CDS_SEC 1
J 0
(-7950 4625);
DISPLAY 0.680851 (-7950 4625);
DISPLAY INVISIBLE (-7950 4625);
FORCEADD OFFPAGE..1
(-8400 4575);
FORCEPROP 2 LAST $XR0 13 
J 0
(-8651 4575);
DISPLAY 0.638298 (-8651 4575);
PAINT MONO (-8651 4575);
FORCEPROP 2 LAST PATH I93
J 0
(-8650 4625);
DISPLAY 0.680851 (-8650 4625);
DISPLAY INVISIBLE (-8650 4625);
FORCEPROP 2 LAST CDS_LIB standard
J 0
(-8400 4575);
DISPLAY INVISIBLE (-8400 4575);
FORCEPROP 1 LAST OFFPAGE TRUE
J 0
(-8075 4450);
DISPLAY 0.872340 (-8075 4450);
PAINT GREEN (-8075 4450);
DISPLAY INVISIBLE (-8075 4450);
FORCEPROP 1 LAST COMMENT_BODY TRUE
J 0
(-8275 4475);
DISPLAY 0.872340 (-8275 4475);
PAINT PEACH (-8275 4475);
DISPLAY INVISIBLE (-8275 4475);
FORCEADD Q_LED..1
R 2
(-6125 2900);
FORCEPROP 1 LAST PART_NUMBER BEBL0277D00
J 2
(-6025 3035);
DISPLAY 0.723404 (-6025 3035);
PAINT GREEN (-6025 3035);
FORCEPROP 1 LAST MATERIAL IC
J 2
(-6025 2980);
DISPLAY 0.723404 (-6025 2980);
PAINT GREEN (-6025 2980);
FORCEPROP 2 LAST PACK_TYPE THLF
J 2
(-6025 3125);
DISPLAY 0.680851 (-6025 3125);
FORCEPROP 2 LAST MANUF_PN HV-312470/260/SUBD-TR1
J 2
(-6025 3175);
DISPLAY 0.680851 (-6025 3175);
FORCEPROP 2 LAST COLOR LED_BLUE
J 2
(-6025 3225);
DISPLAY 0.680851 (-6025 3225);
FORCEPROP 2 LAST CDS_LIB pure_quanta
J 2
(-6125 2900);
DISPLAY INVISIBLE (-6125 2900);
FORCEPROP 1 LAST PATH I94
J 2
(-6250 2980);
DISPLAY 0.723404 (-6250 2980);
PAINT GREEN (-6250 2980);
DISPLAY INVISIBLE (-6250 2980);
FORCEPROP 1 LAST NEEDS_NO_SIZE TRUE
J 2
(-6125 2900);
DISPLAY 0.468085 (-6125 2900);
PAINT GREEN (-6125 2900);
DISPLAY INVISIBLE (-6125 2900);
FORCEPROP 1 LAST LOCATION D14
J 2
(-6025 3085);
DISPLAY 0.723404 (-6025 3085);
PAINT GREEN (-6025 3085);
FORCEPROP 0 LASTPIN (-5975 2900) $PN A
J 0
(-5965 2910);
DISPLAY 0.680851 (-5965 2910);
PAINT MONO (-5965 2910);
FORCEPROP 0 LASTPIN (-6275 2900) $PN C
J 2
(-6285 2910);
DISPLAY 0.680851 (-6285 2910);
PAINT MONO (-6285 2910);
FORCEPROP 0 LAST $SEC 1
J 0
(-6025 3275);
DISPLAY 0.680851 (-6025 3275);
PAINT MONO (-6025 3275);
DISPLAY INVISIBLE (-6025 3275);
FORCEPROP 0 LAST CDS_SEC 1
J 0
(-6025 3275);
DISPLAY 0.680851 (-6025 3275);
DISPLAY INVISIBLE (-6025 3275);
FORCEADD Q_LED..1
R 2
(-6150 2450);
FORCEPROP 2 LAST COLOR LED_BLUE
J 2
(-6050 2775);
DISPLAY 0.680851 (-6050 2775);
FORCEPROP 2 LAST MANUF_PN HV-312470/260/SUBD-TR1
J 2
(-6050 2725);
DISPLAY 0.680851 (-6050 2725);
FORCEPROP 2 LAST PACK_TYPE THLF
J 2
(-6050 2675);
DISPLAY 0.680851 (-6050 2675);
FORCEPROP 1 LAST PART_NUMBER BEBL0277D00
J 2
(-6050 2585);
DISPLAY 0.723404 (-6050 2585);
PAINT GREEN (-6050 2585);
FORCEPROP 1 LAST MATERIAL IC
J 2
(-6050 2530);
DISPLAY 0.723404 (-6050 2530);
PAINT GREEN (-6050 2530);
FORCEPROP 1 LAST NEEDS_NO_SIZE TRUE
J 2
(-6150 2450);
DISPLAY 0.468085 (-6150 2450);
PAINT GREEN (-6150 2450);
DISPLAY INVISIBLE (-6150 2450);
FORCEPROP 1 LAST PATH I95
J 2
(-6275 2530);
DISPLAY 0.723404 (-6275 2530);
PAINT GREEN (-6275 2530);
DISPLAY INVISIBLE (-6275 2530);
FORCEPROP 2 LAST CDS_LIB pure_quanta
J 0
(-6150 2450);
DISPLAY INVISIBLE (-6150 2450);
FORCEPROP 1 LAST LOCATION D15
J 2
(-6050 2635);
DISPLAY 0.723404 (-6050 2635);
PAINT GREEN (-6050 2635);
FORCEPROP 0 LASTPIN (-6000 2450) $PN A
J 0
(-5990 2460);
DISPLAY 0.680851 (-5990 2460);
PAINT MONO (-5990 2460);
FORCEPROP 0 LASTPIN (-6300 2450) $PN C
J 2
(-6310 2460);
DISPLAY 0.680851 (-6310 2460);
PAINT MONO (-6310 2460);
FORCEPROP 0 LAST $SEC 1
J 0
(-6050 2825);
DISPLAY 0.680851 (-6050 2825);
PAINT MONO (-6050 2825);
DISPLAY INVISIBLE (-6050 2825);
FORCEPROP 0 LAST CDS_SEC 1
J 0
(-6050 2825);
DISPLAY 0.680851 (-6050 2825);
DISPLAY INVISIBLE (-6050 2825);
FORCEADD Q_LED..1
R 2
(-4175 5250);
FORCEPROP 2 LAST PACK_TYPE THLF
J 2
(-4075 5475);
DISPLAY 0.680851 (-4075 5475);
FORCEPROP 2 LAST MANUF_PN LTL-R42FSFADH213T
J 2
(-4075 5525);
DISPLAY 0.680851 (-4075 5525);
FORCEPROP 2 LAST COLOR LED_YELLOW
J 2
(-4075 5575);
DISPLAY 0.680851 (-4075 5575);
FORCEPROP 1 LAST PART_NUMBER BEYL0182D00
J 2
(-4075 5385);
DISPLAY 0.723404 (-4075 5385);
PAINT GREEN (-4075 5385);
FORCEPROP 1 LAST MATERIAL IC
J 2
(-4075 5330);
DISPLAY 0.723404 (-4075 5330);
PAINT GREEN (-4075 5330);
FORCEPROP 1 LAST NEEDS_NO_SIZE TRUE
J 2
(-4175 5250);
DISPLAY 0.468085 (-4175 5250);
PAINT GREEN (-4175 5250);
DISPLAY INVISIBLE (-4175 5250);
FORCEPROP 1 LAST PATH I97
J 2
(-4300 5330);
DISPLAY 0.723404 (-4300 5330);
PAINT GREEN (-4300 5330);
DISPLAY INVISIBLE (-4300 5330);
FORCEPROP 2 LAST CDS_LIB pure_quanta
J 2
(-4175 5250);
DISPLAY INVISIBLE (-4175 5250);
FORCEPROP 1 LAST LOCATION D13
J 2
(-4075 5435);
DISPLAY 0.723404 (-4075 5435);
PAINT GREEN (-4075 5435);
FORCEPROP 0 LASTPIN (-4025 5250) $PN A
J 0
(-4015 5260);
DISPLAY 0.680851 (-4015 5260);
PAINT MONO (-4015 5260);
FORCEPROP 0 LASTPIN (-4325 5250) $PN C
J 2
(-4335 5260);
DISPLAY 0.680851 (-4335 5260);
PAINT MONO (-4335 5260);
FORCEPROP 0 LAST $SEC 1
J 0
(-4075 5625);
DISPLAY 0.680851 (-4075 5625);
PAINT MONO (-4075 5625);
DISPLAY INVISIBLE (-4075 5625);
FORCEPROP 0 LAST CDS_SEC 1
J 0
(-4075 5625);
DISPLAY 0.680851 (-4075 5625);
DISPLAY INVISIBLE (-4075 5625);
FORCEADD QUANTA_TITLE_BLOCK_C..1
(0 0);
FORCEPROP 0 LAST CDS_CON_LAST_MODIFIED Fri Aug 25 17:25:47 2023
J 0
(-1885 15);
DISPLAY INVISIBLE (-1885 15);
FORCEPROP 2 LAST Q_DEPT 
J 1
(-3763 49);
DISPLAY 1.957447 (-3763 49);
PAINT GREEN (-3763 49);
FORCEPROP 1 LAST CUSTOM_TXT_CDS <CON_LAST_MODIFIED>
J 0
(-1885 15);
DISPLAY 0.978723 (-1885 15);
FORCEPROP 2 LAST CUSTOM_TXT_CDS <XR_PAGE_TITLE>
J 0
(-7890 5250);
DISPLAY 0.638298 (-7890 5250);
PAINT PINK (-7890 5250);
DISPLAY INVISIBLE (-7890 5250);
FORCEPROP 1 LAST CUSTOM_TXT_CDS <NAME_2>
J 0
(-3175 50);
FORCEPROP 1 LAST CUSTOM_TXT_CDS <NAME_1>
J 0
(-3175 175);
FORCEPROP 1 LAST CUSTOM_TXT_CDS <Q_NUMBER>
J 0
(-1403 103);
DISPLAY 1.212766 (-1403 103);
FORCEPROP 1 LAST CUSTOM_TXT_CDS <Q_PROJ>
J 0
(-2382 102);
DISPLAY 1.212766 (-2382 102);
FORCEPROP 1 LAST CUSTOM_TXT_CDS <Q_REV>
J 0
(-184 103);
DISPLAY 1.212766 (-184 103);
FORCEPROP 1 LAST CUSTOM_TXT_CDS <CON_PAGE_NUM> OF <CON_TOTAL_PAGES>
J 0
(-446 18);
DISPLAY 0.978723 (-446 18);
FORCEPROP 1 LAST Q_TITLE LED
J 0
(-9366 26);
DISPLAY 2.446809 (-9366 26);
PAINT GREEN (-9366 26);
FORCEPROP 2 LAST PAGE_BORDER TRUE
J 0
(-7890 5250);
DISPLAY 0.638298 (-7890 5250);
PAINT PINK (-7890 5250);
DISPLAY INVISIBLE (-7890 5250);
FORCEPROP 2 LAST CDS_LIB pure_quanta
J 0
(0 0);
DISPLAY INVISIBLE (0 0);
FORCEPROP 1 LAST COMMENT_BODY TRUE
J 0
(12 -13);
DISPLAY 0.978723 (12 -13);
PAINT GREEN (12 -13);
DISPLAY INVISIBLE (12 -13);
FORCEPROP 1 LAST CDS_LMAN_SYM_OUTLINE -9475,6775,100,-125
J 0
(0 0);
DISPLAY 0.468085 (0 0);
PAINT GREEN (0 0);
DISPLAY INVISIBLE (0 0);
FORCEPROP 2 LAST CDS_XR_PAGE_TITLE CR-49 : @SCM_LIB.SCM(SCH_1):PAGE49
J 0
(-7890 5250);
DISPLAY 0.638298 (-7890 5250);
PAINT PINK (-7890 5250);
DISPLAY INVISIBLE (-7890 5250);
FORCEADD DESIGN_NOTE..1
(-5475 1075);
FORCEPROP 0 LAST L2 TO ACHIEVE PWR LED FUNCTION
J 0
(-5625 800);
DISPLAY 0.808511 (-5625 800);
PAINT WHITE (-5625 800);
FORCEPROP 0 LAST L3 SWITCH INSIDE FPGA
J 0
(-5625 725);
DISPLAY 0.808511 (-5625 725);
PAINT WHITE (-5625 725);
FORCEPROP 0 LAST L1 IS SHARED WITH NET PWRGD_SYS_PWROK
J 0
(-5625 875);
DISPLAY 0.808511 (-5625 875);
PAINT WHITE (-5625 875);
FORCEPROP 0 LAST L0 NET PWR_LED
J 0
(-5625 950);
DISPLAY 0.808511 (-5625 950);
PAINT WHITE (-5625 950);
FORCEPROP 1 LAST COMMENT_BODY TRUE
J 0
(-5450 1175);
DISPLAY 0.978723 (-5450 1175);
PAINT PEACH (-5450 1175);
DISPLAY INVISIBLE (-5450 1175);
FORCEPROP 2 LAST CDS_LIB logical_power
J 0
(-5475 1075);
DISPLAY INVISIBLE (-5475 1075);
FORCEADD DNS..1
(-6350 1050);
PAINT RED (-6350 1050);
FORCEPROP 2 LAST CDS_LIB mstr_misc
J 0
(-6350 1050);
DISPLAY INVISIBLE (-6350 1050);
FORCEPROP 1 LAST COMMENT_BODY TRUE
R 1
J 0
(-6275 825);
DISPLAY 0.872340 (-6275 825);
PAINT PEACH (-6275 825);
DISPLAY INVISIBLE (-6275 825);
WIRE 16 -1 (-7100 3400)(-7100 3450);
WIRE 16 -1 (-6800 3400)(-7100 3400);
WIRE 16 -1 (-7100 3275)(-7100 3400);
WIRE 16 -1 (-5900 5750)(-5900 5825);
WIRE 16 -1 (-5900 5750)(-5775 5750);
WIRE 16 -1 (-5900 5725)(-5900 5750);
WIRE 16 -1 (-7875 5825)(-7875 5850);
WIRE 16 -1 (-7875 5825)(-7775 5825);
WIRE 16 -1 (-7875 5800)(-7875 5825);
WIRE 16 -1 (-3200 5825)(-3200 5650);
WIRE 16 -1 (-800 3475)(-800 2925);
WIRE 16 -1 (-4975 3450)(-4975 3375);
WIRE 16 -1 (-5075 4650)(-5075 4550);
WIRE 16 -1 (-6925 4800)(-6925 4475);
WIRE 16 -1 (-6925 4800)(-6875 4800);
WIRE 16 -1 (-7150 4875)(-7150 4825);
WIRE 16 -1 (-7875 5525)(-7875 5600);
WIRE 16 -1 (-7775 4825)(-7775 4900);
WIRE 16 -1 (-6350 925)(-6350 875);
WIRE 16 -1 (-6575 1150)(-6575 1250);
WIRE 16 -1 (-7425 1150)(-7425 1250);
WIRE 16 -1 (-7950 975)(-7950 875);
WIRE 16 -1 (-4975 1875)(-4975 1925);
WIRE 16 -1 (-6925 1875)(-6925 1950);
WIRE 16 -1 (-5900 5525)(-5900 5450);
WIRE 16 -1 (-7425 1250)(-7350 1250);
WIRE 16 -1 (-6750 1250)(-6575 1250);
WIRE 16 -1 (-925 2925)(-800 2925);
WIRE 16 -1 (-800 2925)(-800 2450);
WIRE 16 -1 (-925 2450)(-800 2450);
WIRE 16 -1 (-5075 5250)(-5075 5050);
WIRE 16 -1 (-4325 5250)(-5075 5250);
FORCEPROP 2 LAST SIG_NAME ID_LED_D_P3V3_AUX
J 0
(-5110 5260);
DISPLAY 0.851064 (-5110 5260);
WIRE 16 -1 (-3200 5450)(-3200 5250);
WIRE 16 -1 (-4025 5250)(-3200 5250);
FORCEPROP 2 LAST SIG_NAME ID_LED_P3V3_AUX
J 0
(-3935 5260);
DISPLAY 0.851064 (-3935 5260);
WIRE 16 -1 (-6875 4950)(-6950 4950);
WIRE 16 -1 (-6950 4950)(-6950 4575);
WIRE 16 -1 (-7675 4575)(-6950 4575);
FORCEPROP 2 LAST SIG_NAME FM_ID_R_LED
J 0
(-7460 4585);
DISPLAY 0.851064 (-7460 4585);
WIRE 16 -1 (-5775 4800)(-5325 4800);
FORCEPROP 2 LAST SIG_NAME ID_LED_BUF
J 0
(-5710 4810);
DISPLAY 0.680851 (-5710 4810);
WIRE 16 -1 (-8675 5200)(-8025 5200);
FORCEPROP 2 LAST SIG_NAME PCH_BEEP_LED
J 0
(-8685 5210);
DISPLAY 0.851064 (-8685 5210);
WIRE 16 -1 (-4975 2450)(-6000 2450);
FORCEPROP 2 LAST SIG_NAME HDD_LED_P5V_AUX
J 0
(-5835 2460);
DISPLAY 0.808511 (-5835 2460);
WIRE 16 -1 (-4975 2250)(-4975 2450);
WIRE 16 -1 (-4975 3075)(-4975 2450);
WIRE 16 -1 (-8675 5100)(-8025 5100);
FORCEPROP 2 LAST SIG_NAME BMC_ID_BEEP_SEL
J 0
(-8685 5110);
DISPLAY 0.851064 (-8685 5110);
WIRE 16 -1 (-7775 5825)(-7775 5400);
WIRE 16 -1 (-5775 5150)(-5775 5750);
WIRE 16 -1 (-6925 1950)(-6925 2050);
WIRE 16 -1 (-6650 1950)(-6925 1950);
WIRE 16 -1 (-6650 2050)(-6650 1950);
WIRE 16 -1 (-6800 3400)(-6800 3275);
WIRE 16 -1 (-4975 1925)(-4975 2050);
WIRE 16 -1 (-5200 1925)(-4975 1925);
WIRE 16 -1 (-5200 2050)(-5200 1925);
WIRE 16 -1 (-5200 3375)(-5200 3275);
WIRE 16 -1 (-5200 3375)(-4975 3375);
WIRE 16 -1 (-4975 3375)(-4975 3275);
WIRE 16 -1 (-2175 2925)(-1225 2925);
FORCEPROP 2 LAST SIG_NAME FM_UARTSW_LSB_R1_N
J 0
(-1985 2935);
DISPLAY 0.851064 (-1985 2935);
WIRE 16 -1 (-3050 2450)(-2375 2450);
FORCEPROP 2 LAST SIG_NAME FM_UARTSW_MSB_N
J 0
(-3025 2460);
DISPLAY 0.808511 (-3025 2460);
WIRE 16 -1 (-6650 2250)(-6650 2900);
WIRE 16 -1 (-6275 2900)(-6650 2900);
WIRE 16 -1 (-6650 2900)(-7100 2900);
WIRE 16 -1 (-7100 3075)(-7100 2900);
WIRE 16 -1 (-7975 2900)(-7100 2900);
FORCEPROP 2 LAST SIG_NAME PWR_LED_BUF_N_R
J 0
(-7735 2910);
DISPLAY 0.808511 (-7735 2910);
WIRE 16 -1 (-6300 2450)(-6800 2450);
WIRE 16 -1 (-6800 3075)(-6800 2450);
WIRE 16 -1 (-6925 2250)(-6925 2450);
WIRE 16 -1 (-6800 2450)(-6925 2450);
WIRE 16 -1 (-7775 2450)(-6925 2450);
FORCEPROP 2 LAST SIG_NAME HDD_LED_BUF_R
J 0
(-7510 2460);
DISPLAY 0.808511 (-7510 2460);
WIRE 16 -1 (-5200 2900)(-5975 2900);
FORCEPROP 2 LAST SIG_NAME PWR_LED_P5V_AUX
J 0
(-5860 2910);
DISPLAY 0.808511 (-5860 2910);
WIRE 16 -1 (-5200 2250)(-5200 2900);
WIRE 16 -1 (-5200 3075)(-5200 2900);
WIRE 16 -1 (-6000 1350)(-6750 1350);
FORCEPROP 2 LAST SIG_NAME HDD_LED_BUF
J 2
(-6010 1360);
DISPLAY 0.808511 (-6010 1360);
WIRE 16 -1 (-6750 1300)(-6350 1300);
WIRE 16 -1 (-6350 1300)(-6000 1300);
FORCEPROP 2 LAST SIG_NAME HDD_LED_N
J 2
(-6035 1310);
DISPLAY 0.808511 (-6035 1310);
WIRE 16 -1 (-6350 1125)(-6350 1300);
WIRE 16 -1 (-2175 2450)(-1225 2450);
FORCEPROP 2 LAST SIG_NAME FM_UARTSW_MSB_R1_N
J 0
(-1985 2460);
DISPLAY 0.851064 (-1985 2460);
WIRE 16 -1 (-7150 5150)(-7150 5075);
WIRE 16 -1 (-6875 5150)(-7150 5150);
WIRE 16 -1 (-7525 5150)(-7150 5150);
FORCEPROP 2 LAST SIG_NAME BEEP_LED
J 0
(-7337 5160);
DISPLAY 0.680851 (-7337 5160);
WIRE 16 -1 (-8350 4575)(-7875 4575);
FORCEPROP 2 LAST SIG_NAME FM_ID_LED
J 0
(-8325 4585);
DISPLAY 0.808511 (-8325 4585);
WIRE 16 -1 (-8175 2900)(-8900 2900);
FORCEPROP 2 LAST SIG_NAME PWR_LED_BUF_N
J 0
(-8875 2910);
DISPLAY 0.808511 (-8875 2910);
WIRE 16 -1 (-8600 2450)(-7975 2450);
FORCEPROP 2 LAST SIG_NAME HDD_LED_BUF
J 0
(-8575 2460);
DISPLAY 0.808511 (-8575 2460);
WIRE 16 -1 (-3050 2925)(-2375 2925);
FORCEPROP 2 LAST SIG_NAME FM_UARTSW_LSB_N
J 0
(-3025 2935);
DISPLAY 0.808511 (-3025 2935);
WIRE 16 -1 (-7950 1300)(-7950 1175);
WIRE 16 -1 (-7950 1300)(-8100 1300);
WIRE 16 -1 (-7350 1300)(-7950 1300);
FORCEPROP 2 LAST SIG_NAME PWR_LED
J 0
(-7885 1310);
DISPLAY 0.808511 (-7885 1310);
WIRE 16 -1 (-7350 1350)(-8100 1350);
FORCEPROP 2 LAST SIG_NAME PWR_LED_BUF_N
J 0
(-8000 1360);
DISPLAY 0.808511 (-8000 1360);
DOT 1 (-5200 2900);
DOT 1 (-800 2925);
DOT 1 (-6350 1300);
DOT 1 (-5900 5750);
DOT 1 (-7875 5825);
DOT 1 (-7950 1300);
DOT 1 (-7150 5150);
DOT 1 (-4975 1925);
DOT 1 (-4975 3375);
DOT 1 (-6925 2450);
DOT 1 (-4975 2450);
DOT 1 (-7100 3400);
DOT 1 (-7100 2900);
DOT 1 (-6925 1950);
DOT 1 (-6800 2450);
DOT 1 (-6650 2900);
FORCENOTE
HDD LED
(-9025 2625) 0;
DISPLAY LEFT (-9025 2625);
DISPLAY 2.510638 (-9025 2625);
PAINT WHITE (-9025 2625);
FORCENOTE
PWR LED
(-9025 3100) 0;
DISPLAY LEFT (-9025 3100);
DISPLAY 2.510638 (-9025 3100);
PAINT WHITE (-9025 3100);
FORCENOTE
ID LED
(-8500 6250) 0;
DISPLAY LEFT (-8500 6250);
DISPLAY 2.510638 (-8500 6250);
PAINT WHITE (-8500 6250);
FORCENOTE
UART LED
(-4050 3500) 0;
DISPLAY LEFT (-4050 3500);
DISPLAY 2.510638 (-4050 3500);
PAINT WHITE (-4050 3500);
QUIT
